G04 ================== begin FILE IDENTIFICATION RECORD ==================*
G04 Layout Name:  D:/<user>/Wistron_project/16316-1/gbr-0621/16316-1.brd*
G04 Film Name:    L2GND*
G04 File Format:  Gerber RS274X*
G04 File Origin:  Cadence Allegro 16.5-S056*
G04 Origin Date:  Wed Jun 21 09:32:02 2017*
G04 *
G04 Layer:  VIA CLASS/L2GND*
G04 Layer:  PIN/L2GND*
G04 Layer:  ETCH/L2GND*
G04 Layer:  DRAWING FORMAT/LAYER_PCB_STORY*
G04 Layer:  DRAWING FORMAT/LAYER_L2GND*
G04 *
G04 Offset:    (0.00 0.00)*
G04 Mirror:    No*
G04 Mode:      Negative*
G04 Rotation:  0*
G04 FullContactRelief:  No*
G04 UndefLineWidth:     6.00*
G04 ================== end FILE IDENTIFICATION RECORD ====================*
%FSLAX35Y35*MOIN*%
%IR0*IPPOS*OFA0.00000B0.00000*MIA0B0*SFA1.00000B1.00000*%
%AMMACRO16*
4,1,16,.07474,.04645,
.08167,.032766,
.086119,.018086,
.087952,.002857,
.087112,-.012459,
.083625,-.027397,
.077597,-.041502,
.07474,-.04645,
.07836,-.05008,
.085866,-.035712,
.090763,-.020259,
.092902,-.004191,
.092218,.012005,
.088732,.027836,
.082551,.042822,
.07836,.05008,
.07474,.04645,
0.0*
4,1,16,.04645,-.07474,
.032766,-.08167,
.018086,-.086119,
.002857,-.087952,
-.012459,-.087112,
-.027397,-.083625,
-.041502,-.077597,
-.04645,-.07474,
-.05008,-.07836,
-.035712,-.085866,
-.020259,-.090763,
-.004191,-.092902,
.012005,-.092218,
.027836,-.088732,
.042822,-.082551,
.05008,-.07836,
.04645,-.07474,
0.0*
4,1,16,-.07474,-.04645,
-.08167,-.032766,
-.086119,-.018086,
-.087952,-.002857,
-.087112,.012459,
-.083625,.027397,
-.077597,.041502,
-.07474,.04645,
-.07836,.05008,
-.085866,.035712,
-.090763,.020259,
-.092902,.004191,
-.092218,-.012005,
-.088732,-.027836,
-.082551,-.042822,
-.07836,-.05008,
-.07474,-.04645,
0.0*
4,1,16,-.04645,.07474,
-.032766,.08167,
-.018086,.086119,
-.002857,.087952,
.012459,.087112,
.027397,.083625,
.041502,.077597,
.04645,.07474,
.05008,.07836,
.035712,.085866,
.020259,.090763,
.004191,.092902,
-.012005,.092218,
-.027836,.088732,
-.042822,.082551,
-.05008,.07836,
-.04645,.07474,
0.0*
%
%ADD16MACRO16*%
%ADD13C,.03*%
%ADD14C,.04*%
%ADD30C,.043*%
%ADD23C,.07*%
%ADD21C,.036*%
%ADD32C,.028*%
%ADD24C,.058*%
%AMMACRO22*
4,1,15,.00398,.00044,
.003999,.000208,
.004004,-.000025,
.003996,-.000258,
.00398,-.00044,
.00483,-.00129,
.004897,-.001007,
.004947,-.000721,
.004981,-.000432,
.004997,-.000141,
.004997,.000149,
.00498,.00044,
.004946,.000729,
.004895,.001015,
.00483,.00129,
.00398,.00044,
90.*
4,1,15,.00044,-.00398,
.000208,-.003999,
-.000025,-.004004,
-.000258,-.003996,
-.00044,-.00398,
-.00129,-.00483,
-.001007,-.004897,
-.000721,-.004947,
-.000432,-.004981,
-.000141,-.004997,
.000149,-.004997,
.00044,-.00498,
.000729,-.004946,
.001015,-.004895,
.00129,-.00483,
.00044,-.00398,
90.*
4,1,15,-.00398,-.00044,
-.003999,-.000208,
-.004004,.000025,
-.003996,.000258,
-.00398,.00044,
-.00483,.00129,
-.004897,.001007,
-.004947,.000721,
-.004981,.000432,
-.004997,.000141,
-.004997,-.000149,
-.00498,-.00044,
-.004946,-.000729,
-.004895,-.001015,
-.00483,-.00129,
-.00398,-.00044,
90.*
4,1,15,-.00044,.00398,
-.000208,.003999,
.000025,.004004,
.000258,.003996,
.00044,.00398,
.00129,.00483,
.001007,.004897,
.000721,.004947,
.000432,.004981,
.000141,.004997,
-.000149,.004997,
-.00044,.00498,
-.000729,.004946,
-.001015,.004895,
-.00129,.00483,
-.00044,.00398,
90.*
%
%ADD22MACRO22*%
%AMMACRO25*
4,1,15,-.00398,.00044,
-.003999,.000208,
-.004004,-.000025,
-.003996,-.000258,
-.00398,-.00044,
-.00483,-.00129,
-.004897,-.001007,
-.004947,-.000721,
-.004981,-.000432,
-.004997,-.000141,
-.004997,.000149,
-.00498,.00044,
-.004946,.000729,
-.004895,.001015,
-.00483,.00129,
-.00398,.00044,
90.*
4,1,15,-.00044,-.00398,
-.000208,-.003999,
.000025,-.004004,
.000258,-.003996,
.00044,-.00398,
.00129,-.00483,
.001007,-.004897,
.000721,-.004947,
.000432,-.004981,
.000141,-.004997,
-.000149,-.004997,
-.00044,-.00498,
-.000729,-.004946,
-.001015,-.004895,
-.00129,-.00483,
-.00044,-.00398,
90.*
4,1,15,.00398,-.00044,
.003999,-.000208,
.004004,.000025,
.003996,.000258,
.00398,.00044,
.00483,.00129,
.004897,.001007,
.004947,.000721,
.004981,.000432,
.004997,.000141,
.004997,-.000149,
.00498,-.00044,
.004946,-.000729,
.004895,-.001015,
.00483,-.00129,
.00398,-.00044,
90.*
4,1,15,.00044,.00398,
.000208,.003999,
-.000025,.004004,
-.000258,.003996,
-.00044,.00398,
-.00129,.00483,
-.001007,.004897,
-.000721,.004947,
-.000432,.004981,
-.000141,.004997,
.000149,.004997,
.00044,.00498,
.000729,.004946,
.001015,.004895,
.00129,.00483,
.00044,.00398,
90.*
%
%ADD25MACRO25*%
%AMMACRO11*
4,1,15,.00398,.00044,
.003999,.000208,
.004004,-.000025,
.003996,-.000258,
.00398,-.00044,
.00483,-.00129,
.004897,-.001007,
.004947,-.000721,
.004981,-.000432,
.004997,-.000141,
.004997,.000149,
.00498,.00044,
.004946,.000729,
.004895,.001015,
.00483,.00129,
.00398,.00044,
0.0*
4,1,15,.00044,-.00398,
.000208,-.003999,
-.000025,-.004004,
-.000258,-.003996,
-.00044,-.00398,
-.00129,-.00483,
-.001007,-.004897,
-.000721,-.004947,
-.000432,-.004981,
-.000141,-.004997,
.000149,-.004997,
.00044,-.00498,
.000729,-.004946,
.001015,-.004895,
.00129,-.00483,
.00044,-.00398,
0.0*
4,1,15,-.00398,-.00044,
-.003999,-.000208,
-.004004,.000025,
-.003996,.000258,
-.00398,.00044,
-.00483,.00129,
-.004897,.001007,
-.004947,.000721,
-.004981,.000432,
-.004997,.000141,
-.004997,-.000149,
-.00498,-.00044,
-.004946,-.000729,
-.004895,-.001015,
-.00483,-.00129,
-.00398,-.00044,
0.0*
4,1,15,-.00044,.00398,
-.000208,.003999,
.000025,.004004,
.000258,.003996,
.00044,.00398,
.00129,.00483,
.001007,.004897,
.000721,.004947,
.000432,.004981,
.000141,.004997,
-.000149,.004997,
-.00044,.00498,
-.000729,.004946,
-.001015,.004895,
-.00129,.00483,
-.00044,.00398,
0.0*
%
%ADD11MACRO11*%
%AMMACRO27*
4,1,15,-.00398,.00044,
-.003999,.000208,
-.004004,-.000025,
-.003996,-.000258,
-.00398,-.00044,
-.00483,-.00129,
-.004897,-.001007,
-.004947,-.000721,
-.004981,-.000432,
-.004997,-.000141,
-.004997,.000149,
-.00498,.00044,
-.004946,.000729,
-.004895,.001015,
-.00483,.00129,
-.00398,.00044,
0.0*
4,1,15,-.00044,-.00398,
-.000208,-.003999,
.000025,-.004004,
.000258,-.003996,
.00044,-.00398,
.00129,-.00483,
.001007,-.004897,
.000721,-.004947,
.000432,-.004981,
.000141,-.004997,
-.000149,-.004997,
-.00044,-.00498,
-.000729,-.004946,
-.001015,-.004895,
-.00129,-.00483,
-.00044,-.00398,
0.0*
4,1,15,.00398,-.00044,
.003999,-.000208,
.004004,.000025,
.003996,.000258,
.00398,.00044,
.00483,.00129,
.004897,.001007,
.004947,.000721,
.004981,.000432,
.004997,.000141,
.004997,-.000149,
.00498,-.00044,
.004946,-.000729,
.004895,-.001015,
.00483,-.00129,
.00398,-.00044,
0.0*
4,1,15,.00044,.00398,
.000208,.003999,
-.000025,.004004,
-.000258,.003996,
-.00044,.00398,
-.00129,.00483,
-.001007,.004897,
-.000721,.004947,
-.000432,.004981,
-.000141,.004997,
.000149,.004997,
.00044,.00498,
.000729,.004946,
.001015,.004895,
.00129,.00483,
.00044,.00398,
0.0*
%
%ADD27MACRO27*%
%ADD19C,.122*%
%ADD10C,.114*%
%ADD33C,.115*%
%ADD20C,.125*%
%ADD31C,.147*%
%ADD29C,.178*%
%AMMACRO18*
4,1,12,.04693,.01865,
.049456,.010217,
.050478,.001474,
.049968,-.007314,
.047938,-.015879,
.04693,-.01865,
.05075,-.02247,
.053881,-.013316,
.055375,-.003757,
.055186,.005915,
.05332,.015408,
.05075,.02247,
.04693,.01865,
0.0*
4,1,12,.01865,-.04693,
.010217,-.049456,
.001474,-.050478,
-.007314,-.049968,
-.015879,-.047938,
-.01865,-.04693,
-.02247,-.05075,
-.013316,-.053881,
-.003757,-.055375,
.005915,-.055186,
.015408,-.05332,
.02247,-.05075,
.01865,-.04693,
0.0*
4,1,12,-.04693,-.01865,
-.049456,-.010217,
-.050478,-.001474,
-.049968,.007314,
-.047938,.015879,
-.04693,.01865,
-.05075,.02247,
-.053881,.013316,
-.055375,.003757,
-.055186,-.005915,
-.05332,-.015408,
-.05075,-.02247,
-.04693,-.01865,
0.0*
4,1,12,-.01865,.04693,
-.010217,.049456,
-.001474,.050478,
.007314,.049968,
.015879,.047938,
.01865,.04693,
.02247,.05075,
.013316,.053881,
.003757,.055375,
-.005915,.055186,
-.015408,.05332,
-.02247,.05075,
-.01865,.04693,
0.0*
%
%ADD18MACRO18*%
%AMMACRO34*
4,1,15,.00398,.00044,
.003999,.000208,
.004004,-.000025,
.003996,-.000258,
.00398,-.00044,
.00483,-.00129,
.004897,-.001007,
.004947,-.000721,
.004981,-.000432,
.004997,-.000141,
.004997,.000149,
.00498,.00044,
.004946,.000729,
.004895,.001015,
.00483,.00129,
.00398,.00044,
225.*
4,1,15,.00044,-.00398,
.000208,-.003999,
-.000025,-.004004,
-.000258,-.003996,
-.00044,-.00398,
-.00129,-.00483,
-.001007,-.004897,
-.000721,-.004947,
-.000432,-.004981,
-.000141,-.004997,
.000149,-.004997,
.00044,-.00498,
.000729,-.004946,
.001015,-.004895,
.00129,-.00483,
.00044,-.00398,
225.*
4,1,15,-.00398,-.00044,
-.003999,-.000208,
-.004004,.000025,
-.003996,.000258,
-.00398,.00044,
-.00483,.00129,
-.004897,.001007,
-.004947,.000721,
-.004981,.000432,
-.004997,.000141,
-.004997,-.000149,
-.00498,-.00044,
-.004946,-.000729,
-.004895,-.001015,
-.00483,-.00129,
-.00398,-.00044,
225.*
4,1,15,-.00044,.00398,
-.000208,.003999,
.000025,.004004,
.000258,.003996,
.00044,.00398,
.00129,.00483,
.001007,.004897,
.000721,.004947,
.000432,.004981,
.000141,.004997,
-.000149,.004997,
-.00044,.00498,
-.000729,.004946,
-.001015,.004895,
-.00129,.00483,
-.00044,.00398,
225.*
%
%ADD34MACRO34*%
%AMMACRO15*
4,1,15,.00398,.00044,
.003999,.000208,
.004004,-.000025,
.003996,-.000258,
.00398,-.00044,
.00483,-.00129,
.004897,-.001007,
.004947,-.000721,
.004981,-.000432,
.004997,-.000141,
.004997,.000149,
.00498,.00044,
.004946,.000729,
.004895,.001015,
.00483,.00129,
.00398,.00044,
180.*
4,1,15,.00044,-.00398,
.000208,-.003999,
-.000025,-.004004,
-.000258,-.003996,
-.00044,-.00398,
-.00129,-.00483,
-.001007,-.004897,
-.000721,-.004947,
-.000432,-.004981,
-.000141,-.004997,
.000149,-.004997,
.00044,-.00498,
.000729,-.004946,
.001015,-.004895,
.00129,-.00483,
.00044,-.00398,
180.*
4,1,15,-.00398,-.00044,
-.003999,-.000208,
-.004004,.000025,
-.003996,.000258,
-.00398,.00044,
-.00483,.00129,
-.004897,.001007,
-.004947,.000721,
-.004981,.000432,
-.004997,.000141,
-.004997,-.000149,
-.00498,-.00044,
-.004946,-.000729,
-.004895,-.001015,
-.00483,-.00129,
-.00398,-.00044,
180.*
4,1,15,-.00044,.00398,
-.000208,.003999,
.000025,.004004,
.000258,.003996,
.00044,.00398,
.00129,.00483,
.001007,.004897,
.000721,.004947,
.000432,.004981,
.000141,.004997,
-.000149,.004997,
-.00044,.00498,
-.000729,.004946,
-.001015,.004895,
-.00129,.00483,
-.00044,.00398,
180.*
%
%ADD15MACRO15*%
%AMMACRO12*
4,1,15,.00398,.00044,
.003999,.000208,
.004004,-.000025,
.003996,-.000258,
.00398,-.00044,
.00483,-.00129,
.004897,-.001007,
.004947,-.000721,
.004981,-.000432,
.004997,-.000141,
.004997,.000149,
.00498,.00044,
.004946,.000729,
.004895,.001015,
.00483,.00129,
.00398,.00044,
270.*
4,1,15,.00044,-.00398,
.000208,-.003999,
-.000025,-.004004,
-.000258,-.003996,
-.00044,-.00398,
-.00129,-.00483,
-.001007,-.004897,
-.000721,-.004947,
-.000432,-.004981,
-.000141,-.004997,
.000149,-.004997,
.00044,-.00498,
.000729,-.004946,
.001015,-.004895,
.00129,-.00483,
.00044,-.00398,
270.*
4,1,15,-.00398,-.00044,
-.003999,-.000208,
-.004004,.000025,
-.003996,.000258,
-.00398,.00044,
-.00483,.00129,
-.004897,.001007,
-.004947,.000721,
-.004981,.000432,
-.004997,.000141,
-.004997,-.000149,
-.00498,-.00044,
-.004946,-.000729,
-.004895,-.001015,
-.00483,-.00129,
-.00398,-.00044,
270.*
4,1,15,-.00044,.00398,
-.000208,.003999,
.000025,.004004,
.000258,.003996,
.00044,.00398,
.00129,.00483,
.001007,.004897,
.000721,.004947,
.000432,.004981,
.000141,.004997,
-.000149,.004997,
-.00044,.00498,
-.000729,.004946,
-.001015,.004895,
-.00129,.00483,
-.00044,.00398,
270.*
%
%ADD12MACRO12*%
%AMMACRO35*
4,1,15,-.00398,.00044,
-.003999,.000208,
-.004004,-.000025,
-.003996,-.000258,
-.00398,-.00044,
-.00483,-.00129,
-.004897,-.001007,
-.004947,-.000721,
-.004981,-.000432,
-.004997,-.000141,
-.004997,.000149,
-.00498,.00044,
-.004946,.000729,
-.004895,.001015,
-.00483,.00129,
-.00398,.00044,
135.*
4,1,15,-.00044,-.00398,
-.000208,-.003999,
.000025,-.004004,
.000258,-.003996,
.00044,-.00398,
.00129,-.00483,
.001007,-.004897,
.000721,-.004947,
.000432,-.004981,
.000141,-.004997,
-.000149,-.004997,
-.00044,-.00498,
-.000729,-.004946,
-.001015,-.004895,
-.00129,-.00483,
-.00044,-.00398,
135.*
4,1,15,.00398,-.00044,
.003999,-.000208,
.004004,.000025,
.003996,.000258,
.00398,.00044,
.00483,.00129,
.004897,.001007,
.004947,.000721,
.004981,.000432,
.004997,.000141,
.004997,-.000149,
.00498,-.00044,
.004946,-.000729,
.004895,-.001015,
.00483,-.00129,
.00398,-.00044,
135.*
4,1,15,.00044,.00398,
.000208,.003999,
-.000025,.004004,
-.000258,.003996,
-.00044,.00398,
-.00129,.00483,
-.001007,.004897,
-.000721,.004947,
-.000432,.004981,
-.000141,.004997,
.000149,.004997,
.00044,.00498,
.000729,.004946,
.001015,.004895,
.00129,.00483,
.00044,.00398,
135.*
%
%ADD35MACRO35*%
%AMMACRO28*
4,1,15,-.00398,.00044,
-.003999,.000208,
-.004004,-.000025,
-.003996,-.000258,
-.00398,-.00044,
-.00483,-.00129,
-.004897,-.001007,
-.004947,-.000721,
-.004981,-.000432,
-.004997,-.000141,
-.004997,.000149,
-.00498,.00044,
-.004946,.000729,
-.004895,.001015,
-.00483,.00129,
-.00398,.00044,
270.*
4,1,15,-.00044,-.00398,
-.000208,-.003999,
.000025,-.004004,
.000258,-.003996,
.00044,-.00398,
.00129,-.00483,
.001007,-.004897,
.000721,-.004947,
.000432,-.004981,
.000141,-.004997,
-.000149,-.004997,
-.00044,-.00498,
-.000729,-.004946,
-.001015,-.004895,
-.00129,-.00483,
-.00044,-.00398,
270.*
4,1,15,.00398,-.00044,
.003999,-.000208,
.004004,.000025,
.003996,.000258,
.00398,.00044,
.00483,.00129,
.004897,.001007,
.004947,.000721,
.004981,.000432,
.004997,.000141,
.004997,-.000149,
.00498,-.00044,
.004946,-.000729,
.004895,-.001015,
.00483,-.00129,
.00398,-.00044,
270.*
4,1,15,.00044,.00398,
.000208,.003999,
-.000025,.004004,
-.000258,.003996,
-.00044,.00398,
-.00129,.00483,
-.001007,.004897,
-.000721,.004947,
-.000432,.004981,
-.000141,.004997,
.000149,.004997,
.00044,.00498,
.000729,.004946,
.001015,.004895,
.00129,.00483,
.00044,.00398,
270.*
%
%ADD28MACRO28*%
%AMMACRO26*
4,1,15,-.00398,.00044,
-.003999,.000208,
-.004004,-.000025,
-.003996,-.000258,
-.00398,-.00044,
-.00483,-.00129,
-.004897,-.001007,
-.004947,-.000721,
-.004981,-.000432,
-.004997,-.000141,
-.004997,.000149,
-.00498,.00044,
-.004946,.000729,
-.004895,.001015,
-.00483,.00129,
-.00398,.00044,
180.*
4,1,15,-.00044,-.00398,
-.000208,-.003999,
.000025,-.004004,
.000258,-.003996,
.00044,-.00398,
.00129,-.00483,
.001007,-.004897,
.000721,-.004947,
.000432,-.004981,
.000141,-.004997,
-.000149,-.004997,
-.00044,-.00498,
-.000729,-.004946,
-.001015,-.004895,
-.00129,-.00483,
-.00044,-.00398,
180.*
4,1,15,.00398,-.00044,
.003999,-.000208,
.004004,.000025,
.003996,.000258,
.00398,.00044,
.00483,.00129,
.004897,.001007,
.004947,.000721,
.004981,.000432,
.004997,.000141,
.004997,-.000149,
.00498,-.00044,
.004946,-.000729,
.004895,-.001015,
.00483,-.00129,
.00398,-.00044,
180.*
4,1,15,.00044,.00398,
.000208,.003999,
-.000025,.004004,
-.000258,.003996,
-.00044,.00398,
-.00129,.00483,
-.001007,.004897,
-.000721,.004947,
-.000432,.004981,
-.000141,.004997,
.000149,.004997,
.00044,.00498,
.000729,.004946,
.001015,.004895,
.00129,.00483,
.00044,.00398,
180.*
%
%ADD26MACRO26*%
%AMMACRO36*
4,1,15,.00398,.00044,
.003999,.000208,
.004004,-.000025,
.003996,-.000258,
.00398,-.00044,
.00483,-.00129,
.004897,-.001007,
.004947,-.000721,
.004981,-.000432,
.004997,-.000141,
.004997,.000149,
.00498,.00044,
.004946,.000729,
.004895,.001015,
.00483,.00129,
.00398,.00044,
282.*
4,1,15,.00044,-.00398,
.000208,-.003999,
-.000025,-.004004,
-.000258,-.003996,
-.00044,-.00398,
-.00129,-.00483,
-.001007,-.004897,
-.000721,-.004947,
-.000432,-.004981,
-.000141,-.004997,
.000149,-.004997,
.00044,-.00498,
.000729,-.004946,
.001015,-.004895,
.00129,-.00483,
.00044,-.00398,
282.*
4,1,15,-.00398,-.00044,
-.003999,-.000208,
-.004004,.000025,
-.003996,.000258,
-.00398,.00044,
-.00483,.00129,
-.004897,.001007,
-.004947,.000721,
-.004981,.000432,
-.004997,.000141,
-.004997,-.000149,
-.00498,-.00044,
-.004946,-.000729,
-.004895,-.001015,
-.00483,-.00129,
-.00398,-.00044,
282.*
4,1,15,-.00044,.00398,
-.000208,.003999,
.000025,.004004,
.000258,.003996,
.00044,.00398,
.00129,.00483,
.001007,.004897,
.000721,.004947,
.000432,.004981,
.000141,.004997,
-.000149,.004997,
-.00044,.00498,
-.000729,.004946,
-.001015,.004895,
-.00129,.00483,
-.00044,.00398,
282.*
%
%ADD36MACRO36*%
%AMMACRO17*
4,1,13,.03683,.01561,
.038981,.008977,
.039948,.002072,
.039701,-.004896,
.038247,-.011716,
.03683,-.01561,
.04061,-.01939,
.04336,-.012044,
.044793,-.004331,
.044864,.003513,
.043573,.01125,
.040957,.018645,
.04061,.01939,
.03683,.01561,
0.0*
4,1,13,.01561,-.03683,
.008977,-.038981,
.002072,-.039948,
-.004896,-.039701,
-.011716,-.038247,
-.01561,-.03683,
-.01939,-.04061,
-.012044,-.04336,
-.004331,-.044793,
.003513,-.044864,
.01125,-.043573,
.018645,-.040957,
.01939,-.04061,
.01561,-.03683,
0.0*
4,1,13,-.03683,-.01561,
-.038981,-.008977,
-.039948,-.002072,
-.039701,.004896,
-.038247,.011716,
-.03683,.01561,
-.04061,.01939,
-.04336,.012044,
-.044793,.004331,
-.044864,-.003513,
-.043573,-.01125,
-.040957,-.018645,
-.04061,-.01939,
-.03683,-.01561,
0.0*
4,1,13,-.01561,.03683,
-.008977,.038981,
-.002072,.039948,
.004896,.039701,
.011716,.038247,
.01561,.03683,
.01939,.04061,
.012044,.04336,
.004331,.044793,
-.003513,.044864,
-.01125,.043573,
-.018645,.040957,
-.01939,.04061,
-.01561,.03683,
0.0*
%
%ADD17MACRO17*%
%ADD37C,.02*%
%ADD38C,.006*%
%ADD45C,.06604*%
%ADD40C,.11004*%
%ADD43C,.11104*%
%ADD46C,.11804*%
%ADD44C,.37405*%
%ADD39C,.23626*%
%ADD42C,.37406*%
%ADD41C,.23627*%
%ADD47C,.27563*%
G75*
%LPD*%
G75*
G36*
G01X-6000Y-6000D02*
X832772D01*
Y576866D01*
X-6000D01*
Y-6000D01*
G37*
%LPC*%
G75*
G36*
G01X326783Y567862D02*
G02X331652Y562992I-1J-4870D01*
G01Y520719D01*
G03X350756Y498316I22689J1D01*
G01X383620Y493059D01*
X443151D01*
X476035Y498319D01*
G03X495140Y520723I-3584J22404D01*
G01Y562992D01*
G02X500010Y567862I4870J0D01*
G01X818898D01*
G02X823768Y562992I0J-4870D01*
G01Y7874D01*
G02X818898Y3004I-4870J0D01*
G01X7874D01*
G02X3004Y7874I0J4870D01*
G01Y562992D01*
G02X7874Y567862I4870J0D01*
G01X326783D01*
G37*
%LPD*%
G75*
G36*
G01X655786Y118047D02*
X657478D01*
G02X657479Y115025I1J-1511D01*
G01X654331Y115024D01*
G02X653474Y117780I0J1511D01*
G03Y118440I-227J330D01*
G02X652818Y119685I855J1246D01*
G01Y122834D01*
G02X653474Y124080I1511J0D01*
G03Y124739I-227J330D01*
G02Y127229I857J1245D01*
G03Y127888I-227J330D01*
G02X652818Y129134I855J1246D01*
G01Y132283D01*
G02X653179Y133262I1512J-1D01*
G03X652874Y133922I-305J260D01*
G01X651180D01*
G02X651181Y136944I1J1511D01*
G01X652873D01*
G03X653178Y137603I0J400D01*
G02X652818Y138582I1151J979D01*
G01Y141732D01*
G02X653179Y142711I1512J-1D01*
G03X652874Y143370I-305J259D01*
G01X651180D01*
G02X651181Y146394I1J1512D01*
G01X652873D01*
G03X653178Y147052I0J400D01*
G02X652818Y148031I1151J979D01*
G01Y151181D01*
G02X655842I1512J0D01*
G01Y148030D01*
G02X655187Y146786I-1512J1D01*
G03Y146127I227J-329D01*
G02X655186Y143637I-857J-1245D01*
G03Y142977I227J-330D01*
G02X655842Y141732I-855J-1246D01*
G01Y138581D01*
G02X655187Y137337I-1512J1D01*
G03Y136678I227J-329D01*
G02X655186Y134188I-857J-1245D01*
G03Y133528I227J-330D01*
G02X655842Y132283I-855J-1246D01*
G01Y129133D01*
G02X655481Y128155I-1512J2D01*
G03X655786Y127496I305J-259D01*
G01X657481D01*
G02X657480Y124472I-1J-1512D01*
G01X655786D01*
G03X655481Y123813I0J-400D01*
G02X655842Y122834I-1151J-980D01*
G01Y119684D01*
G02X655482Y118706I-1512J1D01*
G03X655786Y118047I305J-259D01*
G37*
G36*
G01X661856Y118988D02*
G02X659217Y119686I-1227J697D01*
G01X659218D01*
Y122833D01*
G02X661857Y123532I1412J1D01*
G03X662552I347J198D01*
G02X665190Y122834I1227J-698D01*
G01Y119685D01*
G02X662552Y118988I-1411J0D01*
G03X661856I-348J-198D01*
G37*
G36*
G01X671305D02*
G02X668666Y119686I-1227J697D01*
G01X668667D01*
Y122834D01*
G02X671306Y123532I1412J1D01*
G03X672002I348J198D01*
G02X674641Y122834I1227J-697D01*
G01X674640D01*
Y119685D01*
X674639D01*
G02X672001Y118988I-1411J0D01*
G03X671305I-348J-198D01*
G37*
G36*
G01X680754D02*
G02X678115Y119686I-1227J697D01*
G01X678116D01*
Y122834D01*
G02X680755Y123532I1412J1D01*
G03X681451I348J198D01*
G02X684090Y122834I1227J-697D01*
G01X684089D01*
Y119685D01*
X684088D01*
G02X681450Y118988I-1411J0D01*
G03X680754I-348J-198D01*
G37*
G36*
G01X690203D02*
G02X687564Y119686I-1227J697D01*
G01X687565D01*
Y122834D01*
G02X690204Y123533I1412J1D01*
G03X690899I347J198D01*
G02X693538Y122835I1227J-698D01*
G01Y119686D01*
G02X690899Y118988I-1412J0D01*
G03X690203I-348J-197D01*
G37*
G36*
G01X406672Y412981D02*
X406676Y412940D01*
X408791Y408991D01*
X408823Y408966D01*
G02X405336Y407098I-1343J-1682D01*
G01X405332Y407139D01*
X403218Y411087D01*
X403186Y411113D01*
G02X406672Y412981I1342J1682D01*
G37*
G36*
G01X414195Y407097D02*
X414192Y407138D01*
X412075Y411088D01*
X412043Y411113D01*
G02X415530Y412982I1343J1682D01*
G01X415533Y412941D01*
X417650Y408991D01*
X417682Y408965D01*
G02X414195Y407097I-1343J-1681D01*
G37*
G36*
G01X406672Y427942D02*
X406676Y427901D01*
X408791Y423951D01*
X408823Y423926D01*
G02X405336Y422058I-1343J-1682D01*
G01X405332Y422099D01*
X403218Y426048D01*
X403186Y426074D01*
G02X406672Y427942I1342J1682D01*
G37*
G36*
G01X414195Y422057D02*
X414192Y422098D01*
X412076Y426048D01*
X412044Y426074D01*
G02X415530Y427943I1342J1682D01*
G01X415533Y427902D01*
X417650Y423951D01*
X417682Y423925D01*
G02X414195Y422057I-1343J-1681D01*
G37*
G36*
G01X390400Y38583D02*
G02X385978I-2211J0D01*
G01Y44096D01*
G02X390400Y44095I2211J-1D01*
G01Y38583D01*
G37*
G36*
G01X383314Y43307D02*
G02X378892I-2211J0D01*
G01Y48820D01*
G02X383314Y48819I2211J-1D01*
G01Y43307D01*
G37*
G36*
G01X376228Y38583D02*
G02X371804I-2212J0D01*
G01Y44096D01*
G02X376228Y44095I2212J-1D01*
G01Y38583D01*
G37*
G36*
G01X369140Y43307D02*
G02X364718I-2211J0D01*
G01Y48820D01*
G02X369140Y48819I2211J-1D01*
G01Y43307D01*
G37*
G36*
G01X362054Y38583D02*
G02X357632I-2211J0D01*
G01Y44096D01*
G02X362054Y44095I2211J-1D01*
G01Y38583D01*
G37*
G36*
G01X354968Y43307D02*
G02X350544I-2212J0D01*
G01Y48820D01*
G02X354968Y48819I2212J-1D01*
G01Y43307D01*
G37*
G36*
G01X347882Y38583D02*
G02X343458I-2212J0D01*
G01Y44096D01*
G02X347882Y44095I2212J-1D01*
G01Y38583D01*
G37*
G36*
G01X340794Y43307D02*
G02X336372I-2211J0D01*
G01Y48820D01*
G02X340794Y48819I2211J-1D01*
G01Y43307D01*
G37*
G36*
G01Y14961D02*
G02X336372I-2211J0D01*
G01Y20474D01*
G02X340794Y20473I2211J-1D01*
G01Y14961D01*
G37*
G36*
G01X347882Y10237D02*
G02X343458I-2212J0D01*
G01Y15749D01*
G02X347882Y15748I2212J-1D01*
G01Y10237D01*
G37*
G36*
G01X354968Y14961D02*
G02X350544I-2212J0D01*
G01Y20474D01*
G02X354968Y20473I2212J-1D01*
G01Y14961D01*
G37*
G36*
G01X362054Y10237D02*
G02X357632I-2211J0D01*
G01Y15749D01*
G02X362054Y15748I2211J-1D01*
G01Y10237D01*
G37*
G36*
G01X369140Y14961D02*
G02X364718I-2211J0D01*
G01Y20474D01*
G02X369140Y20473I2211J-1D01*
G01Y14961D01*
G37*
G36*
G01X376228Y10237D02*
G02X371804I-2212J0D01*
G01Y15749D01*
G02X376228Y15748I2212J-1D01*
G01Y10237D01*
G37*
G36*
G01X383314Y14961D02*
G02X378892I-2211J0D01*
G01Y20474D01*
G02X383314Y20473I2211J-1D01*
G01Y14961D01*
G37*
G36*
G01X390400Y10237D02*
G02X385978I-2211J0D01*
G01Y15749D01*
G02X390400Y15748I2211J-1D01*
G01Y10237D01*
G37*
G36*
G01X391176Y212599D02*
G02X388352I-1412J0D01*
G01Y216537D01*
G02X391176Y216536I1412J-1D01*
G01Y212599D01*
G37*
G36*
G01X454180Y43307D02*
G02X449758I-2211J0D01*
G01Y48820D01*
G02X454180Y48819I2211J-1D01*
G01Y43307D01*
G37*
G36*
G01X447094Y38583D02*
G02X442670I-2212J0D01*
G01Y44096D01*
G02X447094Y44095I2212J-1D01*
G01Y38583D01*
G37*
G36*
G01X440008Y43307D02*
G02X435584I-2212J0D01*
G01Y48820D01*
G02X440008Y48819I2212J-1D01*
G01Y43307D01*
G37*
G36*
G01X432920Y38583D02*
G02X428498I-2211J0D01*
G01Y44096D01*
G02X432920Y44095I2211J-1D01*
G01Y38583D01*
G37*
G36*
G01X425834Y43307D02*
G02X421410I-2212J0D01*
G01Y48820D01*
G02X425834Y48819I2212J-1D01*
G01Y43307D01*
G37*
G36*
G01X418748Y38583D02*
G02X414324I-2212J0D01*
G01Y44096D01*
G02X418748Y44095I2212J-1D01*
G01Y38583D01*
G37*
G36*
G01X411660Y43307D02*
G02X407238I-2211J0D01*
G01Y48820D01*
G02X411660Y48819I2211J-1D01*
G01Y43307D01*
G37*
G36*
G01X404574Y38583D02*
G02X400152I-2211J0D01*
G01Y44096D01*
G02X404574Y44095I2211J-1D01*
G01Y38583D01*
G37*
G36*
G01X397488Y43307D02*
G02X393064I-2212J0D01*
G01Y48820D01*
G02X397488Y48819I2212J-1D01*
G01Y43307D01*
G37*
G36*
G01Y14961D02*
G02X393064I-2212J0D01*
G01Y20474D01*
G02X397488Y20473I2212J-1D01*
G01Y14961D01*
G37*
G36*
G01X404574Y10237D02*
G02X400152I-2211J0D01*
G01Y15749D01*
G02X404574Y15748I2211J-1D01*
G01Y10237D01*
G37*
G36*
G01X411660Y14961D02*
G02X407238I-2211J0D01*
G01Y20474D01*
G02X411660Y20473I2211J-1D01*
G01Y14961D01*
G37*
G36*
G01X418748Y10237D02*
G02X414324I-2212J0D01*
G01Y15749D01*
G02X418748Y15748I2212J-1D01*
G01Y10237D01*
G37*
G36*
G01X425834Y14961D02*
G02X421410I-2212J0D01*
G01Y20474D01*
G02X425834Y20473I2212J-1D01*
G01Y14961D01*
G37*
G36*
G01X432920Y10237D02*
G02X428498I-2211J0D01*
G01Y15749D01*
G02X432920Y15748I2211J-1D01*
G01Y10237D01*
G37*
G36*
G01X440008Y14961D02*
G02X435584I-2212J0D01*
G01Y20474D01*
G02X440008Y20473I2212J-1D01*
G01Y14961D01*
G37*
G36*
G01X447094Y10237D02*
G02X442670I-2212J0D01*
G01Y15749D01*
G02X447094Y15748I2212J-1D01*
G01Y10237D01*
G37*
G36*
G01X454180Y14961D02*
G02X449758I-2211J0D01*
G01Y20474D01*
G02X454180Y20473I2211J-1D01*
G01Y14961D01*
G37*
G36*
G01X395112Y200788D02*
G02X392290I-1411J0D01*
G01Y204726D01*
G02X395112Y204725I1411J-1D01*
G01Y200788D01*
G37*
G36*
G01X399050Y204725D02*
G02X396226I-1412J0D01*
G01Y208663D01*
G02X399050Y208662I1412J-1D01*
G01Y204725D01*
G37*
G36*
G01X406924D02*
G02X404100I-1412J0D01*
G01Y208663D01*
G02X406924Y208662I1412J-1D01*
G01Y204725D01*
G37*
G36*
G01X414798D02*
G02X411974I-1412J0D01*
G01Y208663D01*
G02X414798Y208662I1412J-1D01*
G01Y204725D01*
G37*
G36*
G01X422672D02*
G02X419848I-1412J0D01*
G01Y208663D01*
G02X422672Y208662I1412J-1D01*
G01Y204725D01*
G37*
G36*
G01X430546D02*
G02X427722I-1412J0D01*
G01Y208663D01*
G02X430546Y208662I1412J-1D01*
G01Y204725D01*
G37*
G36*
G01X399050Y216536D02*
G02X396226I-1412J0D01*
G01Y220474D01*
G02X399050Y220473I1412J-1D01*
G01Y216536D01*
G37*
G36*
G01X402986D02*
G02X400164I-1411J0D01*
G01Y220474D01*
G02X402986Y220473I1411J-1D01*
G01Y216536D01*
G37*
G36*
G01X406924D02*
G02X404100I-1412J0D01*
G01Y220474D01*
G02X406924Y220473I1412J-1D01*
G01Y216536D01*
G37*
G36*
G01X410860D02*
G02X408038I-1411J0D01*
G01Y220474D01*
G02X410860Y220473I1411J-1D01*
G01Y216536D01*
G37*
G36*
G01X414798D02*
G02X411974I-1412J0D01*
G01Y220474D01*
G02X414798Y220473I1412J-1D01*
G01Y216536D01*
G37*
G36*
G01X418734D02*
G02X415912I-1411J0D01*
G01Y220474D01*
G02X418734Y220473I1411J-1D01*
G01Y216536D01*
G37*
G36*
G01X422672D02*
G02X419848I-1412J0D01*
G01Y220474D01*
G02X422672Y220473I1412J-1D01*
G01Y216536D01*
G37*
G36*
G01X426608D02*
G02X423786I-1411J0D01*
G01Y220474D01*
G02X426608Y220473I1411J-1D01*
G01Y216536D01*
G37*
G36*
G01X430546D02*
G02X427722I-1412J0D01*
G01Y220474D01*
G02X430546Y220473I1412J-1D01*
G01Y216536D01*
G37*
G36*
G01X434482D02*
G02X431660I-1411J0D01*
G01Y220474D01*
G02X434482Y220473I1411J-1D01*
G01Y216536D01*
G37*
G36*
G01X438420D02*
G02X435596I-1412J0D01*
G01Y220474D01*
G02X438420Y220473I1412J-1D01*
G01Y216536D01*
G37*
G36*
G01X442356D02*
G02X439534I-1411J0D01*
G01Y220474D01*
G02X442356Y220473I1411J-1D01*
G01Y216536D01*
G37*
G36*
G01X446294D02*
G02X443470I-1412J0D01*
G01Y220474D01*
G02X446294Y220473I1412J-1D01*
G01Y216536D01*
G37*
G36*
G01X450230D02*
G02X447408I-1411J0D01*
G01Y220474D01*
G02X450230Y220473I1411J-1D01*
G01Y216536D01*
G37*
G36*
G01Y200788D02*
G02X447408I-1411J0D01*
G01Y204726D01*
G02X450230Y204725I1411J-1D01*
G01Y200788D01*
G37*
G36*
G01X446294Y204725D02*
G02X443470I-1412J0D01*
G01Y208663D01*
G02X446294Y208662I1412J-1D01*
G01Y204725D01*
G37*
G36*
G01X442356Y200788D02*
G02X439534I-1411J0D01*
G01Y204726D01*
G02X442356Y204725I1411J-1D01*
G01Y200788D01*
G37*
G36*
G01X438420Y204725D02*
G02X435596I-1412J0D01*
G01Y208663D01*
G02X438420Y208662I1412J-1D01*
G01Y204725D01*
G37*
G36*
G01X434482Y200788D02*
G02X431660I-1411J0D01*
G01Y204726D01*
G02X434482Y204725I1411J-1D01*
G01Y200788D01*
G37*
G36*
G01X426608D02*
G02X423786I-1411J0D01*
G01Y204726D01*
G02X426608Y204725I1411J-1D01*
G01Y200788D01*
G37*
G36*
G01X418734D02*
G02X415912I-1411J0D01*
G01Y204726D01*
G02X418734Y204725I1411J-1D01*
G01Y200788D01*
G37*
G36*
G01X410860D02*
G02X408038I-1411J0D01*
G01Y204726D01*
G02X410860Y204725I1411J-1D01*
G01Y200788D01*
G37*
G36*
G01X402986D02*
G02X400164I-1411J0D01*
G01Y204726D01*
G02X402986Y204725I1411J-1D01*
G01Y200788D01*
G37*
G36*
G01X409385Y438226D02*
G02X405575Y436184I-1905J-1021D01*
G01X402621Y441698D01*
X402601Y441738D01*
G02X406433Y443738I1927J979D01*
G01X409385Y438226D01*
G37*
G36*
G01X418244D02*
G02X414434Y436184I-1905J-1021D01*
G01X411481Y441695D01*
G02X415291Y443738I1905J1022D01*
G01X418244Y438226D01*
G37*
G36*
G01X409385Y453186D02*
G02X405575Y451144I-1905J-1021D01*
G01X402621Y456658D01*
X402601Y456698D01*
G02X406433Y458698I1927J979D01*
G01X409385Y453186D01*
G37*
G36*
G01X418244D02*
G02X414434Y451144I-1905J-1021D01*
G01X411481Y456655D01*
G02X415291Y458698I1905J1022D01*
G01X418244Y453186D01*
G37*
G36*
G01X517960Y38583D02*
G02X513536I-2212J0D01*
G01Y44096D01*
G02X517960Y44095I2212J-1D01*
G01Y38583D01*
G37*
G36*
G01X510874Y43307D02*
G02X506450I-2212J0D01*
G01Y48820D01*
G02X510874Y48819I2212J-1D01*
G01Y43307D01*
G37*
G36*
G01X503786Y38583D02*
G02X499364I-2211J0D01*
G01Y44096D01*
G02X503786Y44095I2211J-1D01*
G01Y38583D01*
G37*
G36*
G01X496700Y43307D02*
G02X492278I-2211J0D01*
G01Y48820D01*
G02X496700Y48819I2211J-1D01*
G01Y43307D01*
G37*
G36*
G01X489614Y38583D02*
G02X485190I-2212J0D01*
G01Y44096D01*
G02X489614Y44095I2212J-1D01*
G01Y38583D01*
G37*
G36*
G01X482526Y43307D02*
G02X478104I-2211J0D01*
G01Y48820D01*
G02X482526Y48819I2211J-1D01*
G01Y43307D01*
G37*
G36*
G01X475440Y38583D02*
G02X471018I-2211J0D01*
G01Y44096D01*
G02X475440Y44095I2211J-1D01*
G01Y38583D01*
G37*
G36*
G01X468354Y43307D02*
G02X463930I-2212J0D01*
G01Y48820D01*
G02X468354Y48819I2212J-1D01*
G01Y43307D01*
G37*
G36*
G01X461266Y38583D02*
G02X456844I-2211J0D01*
G01Y44096D01*
G02X461266Y44095I2211J-1D01*
G01Y38583D01*
G37*
G36*
G01Y10237D02*
G02X456844I-2211J0D01*
G01Y15749D01*
G02X461266Y15748I2211J-1D01*
G01Y10237D01*
G37*
G36*
G01X468354Y14961D02*
G02X463930I-2212J0D01*
G01Y20474D01*
G02X468354Y20473I2212J-1D01*
G01Y14961D01*
G37*
G36*
G01X475440Y10237D02*
G02X471018I-2211J0D01*
G01Y15749D01*
G02X475440Y15748I2211J-1D01*
G01Y10237D01*
G37*
G36*
G01X482526Y14961D02*
G02X478104I-2211J0D01*
G01Y20474D01*
G02X482526Y20473I2211J-1D01*
G01Y14961D01*
G37*
G36*
G01X489614Y10237D02*
G02X485190I-2212J0D01*
G01Y15749D01*
G02X489614Y15748I2212J-1D01*
G01Y10237D01*
G37*
G36*
G01X496700Y14961D02*
G02X492278I-2211J0D01*
G01Y20474D01*
G02X496700Y20473I2211J-1D01*
G01Y14961D01*
G37*
G36*
G01X503786Y10237D02*
G02X499364I-2211J0D01*
G01Y15749D01*
G02X503786Y15748I2211J-1D01*
G01Y10237D01*
G37*
G36*
G01X510874Y14961D02*
G02X506450I-2212J0D01*
G01Y20474D01*
G02X510874Y20473I2212J-1D01*
G01Y14961D01*
G37*
G36*
G01X517960Y10237D02*
G02X513536I-2212J0D01*
G01Y15749D01*
G02X517960Y15748I2212J-1D01*
G01Y10237D01*
G37*
G36*
G01X493799Y174368D02*
G02X493598Y174570I1J202D01*
G01Y177770D01*
G02X493799Y177972I201J1D01*
G01X494599D01*
G02X494800Y177770I-1J-202D01*
G01Y174570D01*
G02X494599Y174368I-201J-1D01*
G01X493799D01*
G37*
G36*
G01X496099D02*
G02X495898Y174570I1J202D01*
G01Y177770D01*
G02X496099Y177972I201J1D01*
G01X496899D01*
G02X497100Y177770I-1J-202D01*
G01Y174570D01*
G02X496899Y174368I-201J-1D01*
G01X496099D01*
G37*
G36*
G01X503545Y174310D02*
G02X503344Y174512I1J202D01*
G01Y177712D01*
G02X503545Y177914I201J1D01*
G01X504345D01*
G02X504546Y177712I-1J-202D01*
G01Y174512D01*
G02X504345Y174310I-201J-1D01*
G01X503545D01*
G37*
G36*
G01X505845D02*
G02X505644Y174512I1J202D01*
G01Y177712D01*
G02X505845Y177914I201J1D01*
G01X506645D01*
G02X506846Y177712I-1J-202D01*
G01Y174512D01*
G02X506645Y174310I-201J-1D01*
G01X505845D01*
G37*
G36*
G01X513670Y174252D02*
G02X513468Y174454I0J202D01*
G01Y177654D01*
G02X513670Y177856I202J0D01*
G01X514470D01*
G02X514672Y177654I0J-202D01*
G01Y174454D01*
G02X514470Y174252I-202J0D01*
G01X513670D01*
G37*
G36*
G01X511811Y241570D02*
G02Y238746I0J-1412D01*
G01X507873D01*
G02X507874Y241570I1J1412D01*
G01X511811D01*
G37*
G36*
G01X458104Y216536D02*
G02X455282I-1411J0D01*
G01Y220474D01*
G02X458104Y220473I1411J-1D01*
G01Y216536D01*
G37*
G36*
G01X462042D02*
G02X459218I-1412J0D01*
G01Y220474D01*
G02X462042Y220473I1412J-1D01*
G01Y216536D01*
G37*
G36*
G01X465978D02*
G02X463156I-1411J0D01*
G01Y220474D01*
G02X465978Y220473I1411J-1D01*
G01Y216536D01*
G37*
G36*
G01X469916D02*
G02X467092I-1412J0D01*
G01Y220474D01*
G02X469916Y220473I1412J-1D01*
G01Y216536D01*
G37*
G36*
G01X473852D02*
G02X471030I-1411J0D01*
G01Y220474D01*
G02X473852Y220473I1411J-1D01*
G01Y216536D01*
G37*
G36*
G01X477790D02*
G02X474966I-1412J0D01*
G01Y220474D01*
G02X477790Y220473I1412J-1D01*
G01Y216536D01*
G37*
G36*
G01X481726D02*
G02X478904I-1411J0D01*
G01Y220474D01*
G02X481726Y220473I1411J-1D01*
G01Y216536D01*
G37*
G36*
G01X485664D02*
G02X482840I-1412J0D01*
G01Y220474D01*
G02X485664Y220473I1412J-1D01*
G01Y216536D01*
G37*
G36*
G01X489600D02*
G02X486778I-1411J0D01*
G01Y220474D01*
G02X489600Y220473I1411J-1D01*
G01Y216536D01*
G37*
G36*
G01X500000Y237632D02*
G02Y234810I0J-1411D01*
G01X496062D01*
G02X496063Y237632I1J1411D01*
G01X500000D01*
G37*
G36*
G01Y233696D02*
G02Y230872I0J-1412D01*
G01X496062D01*
G02X496063Y233696I1J1412D01*
G01X500000D01*
G37*
G36*
G01Y229758D02*
G02Y226936I0J-1411D01*
G01X496062D01*
G02X496063Y229758I1J1411D01*
G01X500000D01*
G37*
G36*
G01Y225822D02*
G02Y222998I0J-1412D01*
G01X496062D01*
G02X496063Y225822I1J1412D01*
G01X500000D01*
G37*
G36*
G01Y221884D02*
G02Y219062I0J-1411D01*
G01X496062D01*
G02X496063Y221884I1J1411D01*
G01X500000D01*
G37*
G36*
G01Y217948D02*
G02Y215124I0J-1412D01*
G01X496062D01*
G02X496063Y217948I1J1412D01*
G01X500000D01*
G37*
G36*
G01Y214010D02*
G02Y211188I0J-1411D01*
G01X496062D01*
G02X496063Y214010I1J1411D01*
G01X500000D01*
G37*
G36*
G01X503937Y210074D02*
G02Y207250I0J-1412D01*
G01X499999D01*
G02X500000Y210074I1J1412D01*
G01X503937D01*
G37*
G36*
G01X500000Y241570D02*
G02Y238746I0J-1412D01*
G01X496062D01*
G02X496063Y241570I1J1412D01*
G01X500000D01*
G37*
G36*
G01X492678Y180547D02*
G02X489076I-1801J0D01*
G01Y185048D01*
G02X492678Y185047I1801J-1D01*
G01Y180547D01*
G37*
G36*
G01X502104Y180489D02*
G02X498500I-1802J0D01*
G01Y184990D01*
G02X502104Y184989I1802J-1D01*
G01Y180489D01*
G37*
G36*
G01X512228Y180431D02*
G02X508626I-1801J0D01*
G01Y184932D01*
G02X512228Y184931I1801J-1D01*
G01Y180431D01*
G37*
G36*
G01X489600Y204725D02*
G02X486778I-1411J0D01*
G01Y208663D01*
G02X489600Y208662I1411J-1D01*
G01Y204725D01*
G37*
G36*
G01X485664Y200788D02*
G02X482840I-1412J0D01*
G01Y204726D01*
G02X485664Y204725I1412J-1D01*
G01Y200788D01*
G37*
G36*
G01X481726Y204725D02*
G02X478904I-1411J0D01*
G01Y208663D01*
G02X481726Y208662I1411J-1D01*
G01Y204725D01*
G37*
G36*
G01X477790Y200788D02*
G02X474966I-1412J0D01*
G01Y204726D01*
G02X477790Y204725I1412J-1D01*
G01Y200788D01*
G37*
G36*
G01X473852Y204725D02*
G02X471030I-1411J0D01*
G01Y208663D01*
G02X473852Y208662I1411J-1D01*
G01Y204725D01*
G37*
G36*
G01X469916Y200788D02*
G02X467092I-1412J0D01*
G01Y204726D01*
G02X469916Y204725I1412J-1D01*
G01Y200788D01*
G37*
G36*
G01X465978Y204725D02*
G02X463156I-1411J0D01*
G01Y208663D01*
G02X465978Y208662I1411J-1D01*
G01Y204725D01*
G37*
G36*
G01X462042Y200788D02*
G02X459218I-1412J0D01*
G01Y204726D01*
G02X462042Y204725I1412J-1D01*
G01Y200788D01*
G37*
G36*
G01X458104Y204725D02*
G02X455282I-1411J0D01*
G01Y208663D01*
G02X458104Y208662I1411J-1D01*
G01Y204725D01*
G37*
G36*
G01X500000Y304562D02*
G02Y301738I0J-1412D01*
G01X496062D01*
G02X496063Y304562I1J1412D01*
G01X500000D01*
G37*
G36*
G01Y300624D02*
G02Y297802I0J-1411D01*
G01X496062D01*
G02X496063Y300624I1J1411D01*
G01X500000D01*
G37*
G36*
G01Y292750D02*
G02Y289928I0J-1411D01*
G01X496062D01*
G02X496063Y292750I1J1411D01*
G01X500000D01*
G37*
G36*
G01X515748Y245506D02*
G02Y242684I0J-1411D01*
G01X511810D01*
G02X511811Y245506I1J1411D01*
G01X515748D01*
G37*
G36*
G01X511811Y249444D02*
G02Y246620I0J-1412D01*
G01X507873D01*
G02X507874Y249444I1J1412D01*
G01X511811D01*
G37*
G36*
G01X515748Y253380D02*
G02Y250558I0J-1411D01*
G01X511810D01*
G02X511811Y253380I1J1411D01*
G01X515748D01*
G37*
G36*
G01X511811Y257318D02*
G02Y254494I0J-1412D01*
G01X507873D01*
G02X507874Y257318I1J1412D01*
G01X511811D01*
G37*
G36*
G01Y269128D02*
G02Y266306I0J-1411D01*
G01X507873D01*
G02X507874Y269128I1J1411D01*
G01X511811D01*
G37*
G36*
G01Y277002D02*
G02Y274180I0J-1411D01*
G01X507873D01*
G02X507874Y277002I1J1411D01*
G01X511811D01*
G37*
G36*
G01X515748Y280940D02*
G02Y278116I0J-1412D01*
G01X511810D01*
G02X511811Y280940I1J1412D01*
G01X515748D01*
G37*
G36*
G01X511811Y284876D02*
G02Y282054I0J-1411D01*
G01X507873D01*
G02X507874Y284876I1J1411D01*
G01X511811D01*
G37*
G36*
G01X500000Y257318D02*
G02Y254494I0J-1412D01*
G01X496062D01*
G02X496063Y257318I1J1412D01*
G01X500000D01*
G37*
G36*
G01Y253380D02*
G02Y250558I0J-1411D01*
G01X496062D01*
G02X496063Y253380I1J1411D01*
G01X500000D01*
G37*
G36*
G01Y245506D02*
G02Y242684I0J-1411D01*
G01X496062D01*
G02X496063Y245506I1J1411D01*
G01X500000D01*
G37*
G36*
G01Y261254D02*
G02Y258432I0J-1411D01*
G01X496062D01*
G02X496063Y261254I1J1411D01*
G01X500000D01*
G37*
G36*
G01Y269128D02*
G02Y266306I0J-1411D01*
G01X496062D01*
G02X496063Y269128I1J1411D01*
G01X500000D01*
G37*
G36*
G01Y273066D02*
G02Y270242I0J-1412D01*
G01X496062D01*
G02X496063Y273066I1J1412D01*
G01X500000D01*
G37*
G36*
G01Y277002D02*
G02Y274180I0J-1411D01*
G01X496062D01*
G02X496063Y277002I1J1411D01*
G01X500000D01*
G37*
G36*
G01Y280940D02*
G02Y278116I0J-1412D01*
G01X496062D01*
G02X496063Y280940I1J1412D01*
G01X500000D01*
G37*
G36*
G01Y284876D02*
G02Y282054I0J-1411D01*
G01X496062D01*
G02X496063Y284876I1J1411D01*
G01X500000D01*
G37*
G36*
G01Y288814D02*
G02Y285990I0J-1412D01*
G01X496062D01*
G02X496063Y288814I1J1412D01*
G01X500000D01*
G37*
G36*
G01Y249444D02*
G02Y246620I0J-1412D01*
G01X496062D01*
G02X496063Y249444I1J1412D01*
G01X500000D01*
G37*
G36*
G01X515748Y273066D02*
G02Y270242I0J-1412D01*
G01X511810D01*
G02X511811Y273066I1J1412D01*
G01X515748D01*
G37*
G36*
G01Y288814D02*
G02Y285990I0J-1412D01*
G01X511810D01*
G02X511811Y288814I1J1412D01*
G01X515748D01*
G37*
G36*
G01X500000Y296688D02*
G02Y293864I0J-1412D01*
G01X496062D01*
G02X496063Y296688I1J1412D01*
G01X500000D01*
G37*
G36*
G01X515748Y261254D02*
G02Y258432I0J-1411D01*
G01X511810D01*
G02X511811Y261254I1J1411D01*
G01X515748D01*
G37*
G36*
G01X574652Y38583D02*
G02X570230I-2211J0D01*
G01Y44096D01*
G02X574652Y44095I2211J-1D01*
G01Y38583D01*
G37*
G36*
G01X567566Y43307D02*
G02X563144I-2211J0D01*
G01Y48820D01*
G02X567566Y48819I2211J-1D01*
G01Y43307D01*
G37*
G36*
G01X560480Y38583D02*
G02X556056I-2212J0D01*
G01Y44096D01*
G02X560480Y44095I2212J-1D01*
G01Y38583D01*
G37*
G36*
G01X553392Y43307D02*
G02X548970I-2211J0D01*
G01Y48820D01*
G02X553392Y48819I2211J-1D01*
G01Y43307D01*
G37*
G36*
G01X546306Y38583D02*
G02X541884I-2211J0D01*
G01Y44096D01*
G02X546306Y44095I2211J-1D01*
G01Y38583D01*
G37*
G36*
G01X539220Y43307D02*
G02X534796I-2212J0D01*
G01Y48820D01*
G02X539220Y48819I2212J-1D01*
G01Y43307D01*
G37*
G36*
G01X532134Y38583D02*
G02X527710I-2212J0D01*
G01Y44096D01*
G02X532134Y44095I2212J-1D01*
G01Y38583D01*
G37*
G36*
G01X525046Y43307D02*
G02X520624I-2211J0D01*
G01Y48820D01*
G02X525046Y48819I2211J-1D01*
G01Y43307D01*
G37*
G36*
G01Y14961D02*
G02X520624I-2211J0D01*
G01Y20474D01*
G02X525046Y20473I2211J-1D01*
G01Y14961D01*
G37*
G36*
G01X532134Y10237D02*
G02X527710I-2212J0D01*
G01Y15749D01*
G02X532134Y15748I2212J-1D01*
G01Y10237D01*
G37*
G36*
G01X539220Y14961D02*
G02X534796I-2212J0D01*
G01Y20474D01*
G02X539220Y20473I2212J-1D01*
G01Y14961D01*
G37*
G36*
G01X546306Y10237D02*
G02X541884I-2211J0D01*
G01Y15749D01*
G02X546306Y15748I2211J-1D01*
G01Y10237D01*
G37*
G36*
G01X553392Y14961D02*
G02X548970I-2211J0D01*
G01Y20474D01*
G02X553392Y20473I2211J-1D01*
G01Y14961D01*
G37*
G36*
G01X560480Y10237D02*
G02X556056I-2212J0D01*
G01Y15749D01*
G02X560480Y15748I2212J-1D01*
G01Y10237D01*
G37*
G36*
G01X567566Y14961D02*
G02X563144I-2211J0D01*
G01Y20474D01*
G02X567566Y20473I2211J-1D01*
G01Y14961D01*
G37*
G36*
G01X574652Y10237D02*
G02X570230I-2211J0D01*
G01Y15749D01*
G02X574652Y15748I2211J-1D01*
G01Y10237D01*
G37*
G36*
G01X515970Y174252D02*
G02X515768Y174454I0J202D01*
G01Y177654D01*
G02X515970Y177856I202J0D01*
G01X516770D01*
G02X516972Y177654I0J-202D01*
G01Y174454D01*
G02X516770Y174252I-202J0D01*
G01X515970D01*
G37*
G36*
G01X523795Y174194D02*
G02X523594Y174396I1J202D01*
G01Y177596D01*
G02X523795Y177798I201J1D01*
G01X524595D01*
G02X524796Y177596I-1J-202D01*
G01Y174396D01*
G02X524595Y174194I-201J-1D01*
G01X523795D01*
G37*
G36*
G01X526095D02*
G02X525894Y174396I1J202D01*
G01Y177596D01*
G02X526095Y177798I201J1D01*
G01X526895D01*
G02X527096Y177596I-1J-202D01*
G01Y174396D01*
G02X526895Y174194I-201J-1D01*
G01X526095D01*
G37*
G36*
G01X574170Y131409D02*
G02X577694Y132157I1762J374D01*
G01X578620Y127796D01*
X578621Y127794D01*
G02X575106Y127007I-1753J-413D01*
G01X574170Y131409D01*
G37*
G36*
G01X559730Y237686D02*
G02X559528Y237888I0J202D01*
G01Y238688D01*
G02X559730Y238890I202J0D01*
G01X562930D01*
G02X563132Y238688I0J-202D01*
G01Y237888D01*
G02X562930Y237686I-202J0D01*
G01X559730D01*
G37*
G36*
G01Y235386D02*
G02X559528Y235588I0J202D01*
G01Y236388D01*
G02X559730Y236590I202J0D01*
G01X562930D01*
G02X563132Y236388I0J-202D01*
G01Y235588D01*
G02X562930Y235386I-202J0D01*
G01X559730D01*
G37*
G36*
G01X561365Y228948D02*
G02X561164Y229150I1J202D01*
G01Y229950D01*
G02X561365Y230152I201J1D01*
G01X564565D01*
G02X564766Y229950I-1J-202D01*
G01Y229150D01*
G02X564565Y228948I-201J-1D01*
G01X561365D01*
G37*
G36*
G01Y226648D02*
G02X561164Y226850I1J202D01*
G01Y227650D01*
G02X561365Y227852I201J1D01*
G01X564565D01*
G02X564766Y227650I-1J-202D01*
G01Y226850D01*
G02X564565Y226648I-201J-1D01*
G01X561365D01*
G37*
G36*
G01X547365Y238846D02*
G02Y242430I0J1792D01*
G01X551866D01*
G02X551865Y238846I-1J-1792D01*
G01X547365D01*
G37*
G36*
G01X549000Y230108D02*
G02Y233692I0J1792D01*
G01X553501D01*
G02X553500Y230108I-1J-1792D01*
G01X549000D01*
G37*
G36*
G01X522354Y180373D02*
G02X518750I-1802J0D01*
G01Y184874D01*
G02X522354Y184873I1802J-1D01*
G01Y180373D01*
G37*
G36*
G01X560519Y252844D02*
G02X560318Y253046I1J202D01*
G01Y253846D01*
G02X560519Y254048I201J1D01*
G01X563719D01*
G02X563920Y253846I-1J-202D01*
G01Y253046D01*
G02X563719Y252844I-201J-1D01*
G01X560519D01*
G37*
G36*
G01X558840Y245258D02*
G02X558638Y245459I-1J201D01*
G01Y246259D01*
G02X558840Y246460I202J-1D01*
G01X562040D01*
G02X562242Y246259I1J-201D01*
G01Y245459D01*
G02X562040Y245258I-202J1D01*
G01X558840D01*
G37*
G36*
G01Y242958D02*
G02X558638Y243159I-1J201D01*
G01Y243959D01*
G02X558840Y244160I202J-1D01*
G01X562040D01*
G02X562242Y243959I1J-201D01*
G01Y243159D01*
G02X562040Y242958I-202J1D01*
G01X558840D01*
G37*
G36*
G01X560519Y250544D02*
G02X560318Y250746I1J202D01*
G01Y251546D01*
G02X560519Y251748I201J1D01*
G01X563719D01*
G02X563920Y251546I-1J-202D01*
G01Y250746D01*
G02X563719Y250544I-201J-1D01*
G01X560519D01*
G37*
G36*
G01X534813Y298278D02*
G02X534612Y298480I1J202D01*
G01Y299280D01*
G02X534813Y299482I201J1D01*
G01X538013D01*
G02X538214Y299280I-1J-202D01*
G01Y298480D01*
G02X538013Y298278I-201J-1D01*
G01X534813D01*
G37*
G36*
G01Y296078D02*
G02X534612Y296280I1J202D01*
G01Y297080D01*
G02X534813Y297282I201J1D01*
G01X538013D01*
G02X538214Y297080I-1J-202D01*
G01Y296280D01*
G02X538013Y296078I-201J-1D01*
G01X534813D01*
G37*
G36*
G01X546217Y254004D02*
G02Y257588I0J1792D01*
G01X550718D01*
G02X550717Y254004I-1J-1792D01*
G01X546217D01*
G37*
G36*
G01X546475Y246418D02*
G02Y250000I0J1791D01*
G01X550976D01*
G02X550975Y246418I-1J-1791D01*
G01X546475D01*
G37*
G36*
G01X545015Y302778D02*
X545129Y302792D01*
X549757D01*
X549871Y302778D01*
G02Y299782I-178J-1498D01*
G01X549757Y299768D01*
X545193D01*
X545192Y299770D01*
X545116Y299773D01*
G02X545015Y302778I76J1507D01*
G37*
G36*
G01X534728Y311096D02*
G02X534526Y311298I0J202D01*
G01Y312098D01*
G02X534728Y312300I202J0D01*
G01X537928D01*
G02X538130Y312098I0J-202D01*
G01Y311298D01*
G02X537928Y311096I-202J0D01*
G01X534728D01*
G37*
G36*
G01Y313296D02*
G02X534526Y313498I0J202D01*
G01Y314298D01*
G02X534728Y314500I202J0D01*
G01X537928D01*
G02X538130Y314298I0J-202D01*
G01Y313498D01*
G02X537928Y313296I-202J0D01*
G01X534728D01*
G37*
G36*
G01X534548Y305820D02*
G02X534346Y306021I-1J201D01*
G01Y306821D01*
G02X534548Y307022I202J-1D01*
G01X537748D01*
G02X537950Y306821I1J-201D01*
G01Y306021D01*
G02X537748Y305820I-202J1D01*
G01X534548D01*
G37*
G36*
G01Y303620D02*
G02X534346Y303821I-1J201D01*
G01Y304621D01*
G02X534548Y304822I202J-1D01*
G01X537748D01*
G02X537950Y304621I1J-201D01*
G01Y303821D01*
G02X537748Y303620I-202J1D01*
G01X534548D01*
G37*
G36*
G01X534800Y318798D02*
G02X534598Y319000I0J202D01*
G01Y319800D01*
G02X534800Y320002I202J0D01*
G01X538000D01*
G02X538202Y319800I0J-202D01*
G01Y319000D01*
G02X538000Y318798I-202J0D01*
G01X534800D01*
G37*
G36*
G01Y316598D02*
G02X534598Y316800I0J202D01*
G01Y317600D01*
G02X534800Y317802I202J0D01*
G01X538000D01*
G02X538202Y317600I0J-202D01*
G01Y316800D01*
G02X538000Y316598I-202J0D01*
G01X534800D01*
G37*
G36*
G01X546449Y325547D02*
X546563Y325560D01*
X551191D01*
X551305Y325547D01*
G02Y322551I-178J-1498D01*
G01X551191Y322538D01*
X546627D01*
X546626Y322539D01*
X546550Y322542D01*
G02X546449Y325547I76J1507D01*
G37*
G36*
G01X545100Y317236D02*
X545214Y317250D01*
X549842D01*
X549956Y317236D01*
G02Y314240I-178J-1498D01*
G01X549842Y314226D01*
X545278D01*
X545277Y314228D01*
X545201Y314231D01*
G02X545100Y317236I76J1507D01*
G37*
G36*
G01X545043Y310269D02*
X545157Y310282D01*
X549721D01*
X549722Y310281D01*
X549798Y310278D01*
G02X549899Y307273I-76J-1507D01*
G01X549785Y307260D01*
X545157D01*
X545043Y307273D01*
G02Y310269I178J1498D01*
G37*
G36*
G01X588826Y38583D02*
G02X584402I-2212J0D01*
G01Y44096D01*
G02X588826Y44095I2212J-1D01*
G01Y38583D01*
G37*
G36*
G01X581740Y43307D02*
G02X577316I-2212J0D01*
G01Y48820D01*
G02X581740Y48819I2212J-1D01*
G01Y43307D01*
G37*
G36*
G01Y14961D02*
G02X577316I-2212J0D01*
G01Y20474D01*
G02X581740Y20473I2212J-1D01*
G01Y14961D01*
G37*
G36*
G01X588826Y10237D02*
G02X584402I-2212J0D01*
G01Y15749D01*
G02X588826Y15748I2212J-1D01*
G01Y10237D01*
G37*
G36*
G01X579151Y159744D02*
G02X578912Y159899I-42J197D01*
G01X578746Y160682D01*
G02X578901Y160920I197J41D01*
G01X579390Y161024D01*
X581542Y161482D01*
X582031Y161586D01*
G02X582270Y161431I42J-197D01*
G01X582436Y160648D01*
G02X582281Y160410I-197J-41D01*
G01X581792Y160306D01*
X579640Y159848D01*
X579151Y159744D01*
G37*
G36*
G01X579629Y157495D02*
G02X579390Y157650I-42J197D01*
G01X579224Y158433D01*
G02X579379Y158671I197J41D01*
G01X579868Y158775D01*
X582020Y159233D01*
X582509Y159337D01*
G02X582748Y159182I42J-197D01*
G01X582914Y158399D01*
G02X582759Y158161I-197J-41D01*
G01X582270Y158057D01*
X580118Y157599D01*
X579629Y157495D01*
G37*
G36*
G01X587008Y178059D02*
G02X590532Y178807I1762J374D01*
G01X591458Y174446D01*
X591459Y174444D01*
G02X587944Y173657I-1753J-413D01*
G01X587008Y178059D01*
G37*
G36*
G01X583383Y162435D02*
G02X586907Y163183I1762J374D01*
G01X587833Y158822D01*
X587834Y158820D01*
G02X584319Y158033I-1753J-413D01*
G01X583383Y162435D01*
G37*
G36*
G01X592704Y153607D02*
G02X596228Y154355I1762J374D01*
G01X597154Y149994D01*
X597155Y149992D01*
G02X593640Y149205I-1753J-413D01*
G01X592704Y153607D01*
G37*
G36*
G01X585372Y142248D02*
G02X588896Y142996I1762J374D01*
G01X589822Y138635D01*
X589823Y138633D01*
G02X586308Y137846I-1753J-413D01*
G01X585372Y142248D01*
G37*
G36*
G01X589961Y218883D02*
X590897Y214481D01*
G02X587373Y213733I-1762J-374D01*
G01X586447Y218094D01*
X586446Y218096D01*
G02X589961Y218883I1753J413D01*
G37*
G36*
G01X582312Y202511D02*
G02X585836Y203259I1762J374D01*
G01X586762Y198898D01*
X586763Y198896D01*
G02X583248Y198109I-1753J-413D01*
G01X582312Y202511D01*
G37*
G36*
G01X578187Y186887D02*
G02X581711Y187635I1762J374D01*
G01X582637Y183274D01*
X582638Y183272D01*
G02X579123Y182485I-1753J-413D01*
G01X578187Y186887D01*
G37*
G36*
G01X695876Y90958D02*
G02X692854I-1511J0D01*
G01Y94459D01*
G02X695876Y94458I1511J-1D01*
G01Y90958D01*
G37*
G36*
G01X687790Y90994D02*
G02X684768I-1511J0D01*
G01Y94495D01*
G02X687790Y94494I1511J-1D01*
G01Y90994D01*
G37*
G36*
G01X679736Y90996D02*
G02X676714I-1511J0D01*
G01Y94497D01*
G02X679736Y94496I1511J-1D01*
G01Y90996D01*
G37*
G36*
G01X671658Y91005D02*
G02X668634I-1512J0D01*
G01Y94506D01*
G02X671658Y94505I1512J-1D01*
G01Y91005D01*
G37*
G36*
G01X663558Y91039D02*
G02X660536I-1511J0D01*
G01Y94540D01*
G02X663558Y94539I1511J-1D01*
G01Y91039D01*
G37*
G36*
G01X655548Y91208D02*
G02X652526I-1511J0D01*
G01Y94709D01*
G02X655548Y94708I1511J-1D01*
G01Y91208D01*
G37*
G36*
G01X710872Y43307D02*
G02X706450I-2211J0D01*
G01Y48820D01*
G02X710872Y48819I2211J-1D01*
G01Y43307D01*
G37*
G36*
G01X753392D02*
G02X748970I-2211J0D01*
G01Y48820D01*
G02X753392Y48819I2211J-1D01*
G01Y43307D01*
G37*
G36*
G01X717960Y38583D02*
G02X713536I-2212J0D01*
G01Y44096D01*
G02X717960Y44095I2212J-1D01*
G01Y38583D01*
G37*
G36*
G01X725046Y43307D02*
G02X720622I-2212J0D01*
G01Y48820D01*
G02X725046Y48819I2212J-1D01*
G01Y43307D01*
G37*
G36*
G01X760478Y38583D02*
G02X756056I-2211J0D01*
G01Y44096D01*
G02X760478Y44095I2211J-1D01*
G01Y38583D01*
G37*
G36*
G01X746306D02*
G02X741882I-2212J0D01*
G01Y44096D01*
G02X746306Y44095I2212J-1D01*
G01Y38583D01*
G37*
G36*
G01X739218Y43307D02*
G02X734796I-2211J0D01*
G01Y48820D01*
G02X739218Y48819I2211J-1D01*
G01Y43307D01*
G37*
G36*
G01X732132Y38583D02*
G02X727710I-2211J0D01*
G01Y44096D01*
G02X732132Y44095I2211J-1D01*
G01Y38583D01*
G37*
G36*
G01X710872Y14961D02*
G02X706450I-2211J0D01*
G01Y20474D01*
G02X710872Y20473I2211J-1D01*
G01Y14961D01*
G37*
G36*
G01X717960Y10237D02*
G02X713536I-2212J0D01*
G01Y15749D01*
G02X717960Y15748I2212J-1D01*
G01Y10237D01*
G37*
G36*
G01X725046Y14961D02*
G02X720622I-2212J0D01*
G01Y20474D01*
G02X725046Y20473I2212J-1D01*
G01Y14961D01*
G37*
G36*
G01X732132Y10237D02*
G02X727710I-2211J0D01*
G01Y15749D01*
G02X732132Y15748I2211J-1D01*
G01Y10237D01*
G37*
G36*
G01X739218Y14961D02*
G02X734796I-2211J0D01*
G01Y20474D01*
G02X739218Y20473I2211J-1D01*
G01Y14961D01*
G37*
G36*
G01X746306Y10237D02*
G02X741882I-2212J0D01*
G01Y15749D01*
G02X746306Y15748I2212J-1D01*
G01Y10237D01*
G37*
G36*
G01X753392Y14961D02*
G02X748970I-2211J0D01*
G01Y20474D01*
G02X753392Y20473I2211J-1D01*
G01Y14961D01*
G37*
G36*
G01X760478Y10237D02*
G02X756056I-2211J0D01*
G01Y15749D01*
G02X760478Y15748I2211J-1D01*
G01Y10237D01*
G37*
G36*
G01X710872Y29134D02*
G02X706450I-2211J0D01*
G01Y34647D01*
G02X710872Y34646I2211J-1D01*
G01Y29134D01*
G37*
G36*
G01X711890Y92899D02*
G02X708866I-1512J0D01*
G01Y96400D01*
G02X711890Y96399I1512J-1D01*
G01Y92899D01*
G37*
G36*
G01X703902Y91010D02*
G02X700880I-1511J0D01*
G01Y94511D01*
G02X703902Y94510I1511J-1D01*
G01Y91010D01*
G37*
G36*
G01X570885Y126671D02*
G02X570647Y126825I-42J196D01*
G01X570481Y127608D01*
G02X570635Y127845I196J41D01*
G01X571124Y127949D01*
X573276Y128407D01*
X573765Y128511D01*
G02X573807Y128515I40J-196D01*
G02X574003Y128357I0J-200D01*
G01X574169Y127574D01*
G02X574015Y127337I-196J-41D01*
G01X573526Y127233D01*
X571374Y126775D01*
X570885Y126671D01*
G37*
G36*
G01X570407Y128921D02*
G02X570169Y129075I-42J196D01*
G01X570003Y129858D01*
G02X570157Y130095I196J41D01*
G01X570646Y130199D01*
X572798Y130657D01*
X573287Y130761D01*
G02X573525Y130607I42J-196D01*
G01X573691Y129824D01*
G02X573537Y129587I-196J-41D01*
G01X573048Y129483D01*
X570896Y129025D01*
X570407Y128921D01*
G37*
G36*
G01X581989Y137490D02*
G02X581751Y137644I-42J196D01*
G01X581585Y138427D01*
G02X581739Y138664I196J41D01*
G01X582228Y138768D01*
X584380Y139226D01*
X584869Y139330D01*
G02X585107Y139176I42J-196D01*
G01X585273Y138393D01*
G02X585119Y138156I-196J-41D01*
G01X584630Y138052D01*
X582478Y137594D01*
X581989Y137490D01*
G37*
G36*
G01X98530Y153329D02*
X94041Y148840D01*
X83021D01*
X71931Y137750D01*
X20679D01*
X17920Y140509D01*
Y251471D01*
X20469Y254020D01*
X94181D01*
X98530Y249671D01*
Y153329D01*
G37*
G36*
G01X581511Y139739D02*
G02X581273Y139893I-42J196D01*
G01X581107Y140676D01*
G02X581261Y140913I196J41D01*
G01X581750Y141017D01*
X583902Y141475D01*
X584391Y141579D01*
G02X584629Y141425I42J-196D01*
G01X584795Y140642D01*
G02X584641Y140405I-196J-41D01*
G01X584152Y140301D01*
X582000Y139843D01*
X581511Y139739D01*
G37*
G36*
G01X588950Y148668D02*
G02X588712Y148822I-42J196D01*
G01X588546Y149605D01*
G02X588700Y149842I196J41D01*
G01X589189Y149946D01*
X591341Y150404D01*
X591830Y150508D01*
G02X592068Y150354I42J-196D01*
G01X592234Y149571D01*
G02X592080Y149334I-196J-41D01*
G01X591591Y149230D01*
X589439Y148772D01*
X588950Y148668D01*
G37*
G36*
G01X588472Y150917D02*
G02X588234Y151071I-42J196D01*
G01X588068Y151854D01*
G02X588222Y152091I196J41D01*
G01X588711Y152195D01*
X590863Y152653D01*
X591352Y152757D01*
G02X591590Y152603I42J-196D01*
G01X591756Y151820D01*
G02X591602Y151583I-196J-41D01*
G01X591113Y151479D01*
X588961Y151021D01*
X588472Y150917D01*
G37*
G36*
G01X583722Y173321D02*
G02X583484Y173475I-42J196D01*
G01X583318Y174258D01*
G02X583472Y174495I196J41D01*
G01X583961Y174599D01*
X586113Y175057D01*
X586602Y175161D01*
G02X586840Y175007I42J-196D01*
G01X587006Y174224D01*
G02X586852Y173987I-196J-41D01*
G01X586363Y173883D01*
X584211Y173425D01*
X583722Y173321D01*
G37*
G36*
G01X583244Y175571D02*
G02X583006Y175725I-42J196D01*
G01X582840Y176508D01*
G02X582994Y176745I196J41D01*
G01X583483Y176849D01*
X585635Y177307D01*
X586124Y177411D01*
G02X586362Y177257I42J-196D01*
G01X586528Y176474D01*
G02X586374Y176237I-196J-41D01*
G01X585885Y176133D01*
X583733Y175675D01*
X583244Y175571D01*
G37*
G36*
G01X574825Y182031D02*
G02X574587Y182185I-42J196D01*
G01X574421Y182968D01*
G02X574575Y183205I196J41D01*
G01X575064Y183309D01*
X577216Y183767D01*
X577705Y183871D01*
G02X577943Y183717I42J-196D01*
G01X578109Y182934D01*
G02X577955Y182697I-196J-41D01*
G01X577466Y182593D01*
X575314Y182135D01*
X574825Y182031D01*
G37*
G36*
G01X574347Y184280D02*
G02X574109Y184434I-42J196D01*
G01X573943Y185217D01*
G02X574097Y185454I196J41D01*
G01X574586Y185558D01*
X576738Y186016D01*
X577227Y186120D01*
G02X577465Y185966I42J-196D01*
G01X577631Y185183D01*
G02X577477Y184946I-196J-41D01*
G01X576988Y184842D01*
X574836Y184384D01*
X574347Y184280D01*
G37*
G36*
G01X579027Y197773D02*
G02X578789Y197927I-42J196D01*
G01X578623Y198710D01*
G02X578777Y198947I196J41D01*
G01X579266Y199051D01*
X581418Y199509D01*
X581907Y199613D01*
G02X582145Y199459I42J-196D01*
G01X582311Y198676D01*
G02X582157Y198439I-196J-41D01*
G01X581668Y198335D01*
X579516Y197877D01*
X579027Y197773D01*
G37*
G36*
G01X578549Y200022D02*
G02X578311Y200176I-42J196D01*
G01X578145Y200959D01*
G02X578299Y201196I196J41D01*
G01X578788Y201300D01*
X580940Y201758D01*
X581429Y201862D01*
G02X581667Y201708I42J-196D01*
G01X581833Y200925D01*
G02X581679Y200688I-196J-41D01*
G01X581190Y200584D01*
X579038Y200126D01*
X578549Y200022D01*
G37*
G36*
G01X582957Y213356D02*
G02X582719Y213510I-42J196D01*
G01X582553Y214293D01*
G02X582707Y214530I196J41D01*
G01X583196Y214634D01*
X585348Y215092D01*
X585837Y215196D01*
G02X586075Y215042I42J-196D01*
G01X586241Y214259D01*
G02X586087Y214022I-196J-41D01*
G01X585598Y213918D01*
X583446Y213460D01*
X582957Y213356D01*
G37*
G36*
G01X582478Y215605D02*
G02X582436Y215601I-40J196D01*
G02X582240Y215759I0J200D01*
G01X582074Y216542D01*
G02X582228Y216779I196J41D01*
G01X582717Y216883D01*
X584869Y217341D01*
X585358Y217445D01*
G02X585400Y217449I40J-196D01*
G02X585442Y217445I2J-200D01*
G02X585596Y217291I-42J-196D01*
G01X585762Y216508D01*
G02X585608Y216271I-196J-41D01*
G01X585119Y216167D01*
X582967Y215709D01*
X582478Y215605D01*
G37*
G54D45*
X137795Y472441D03*
X98425D03*
G54D40*
X798456Y26432D03*
X81539Y542850D03*
X27058Y25484D03*
G54D43*
X437008Y460630D03*
X389764D03*
G54D46*
X116063Y14567D03*
G54D44*
X295276Y531496D03*
G54D39*
X781496Y198819D03*
X531496Y371299D03*
G54D42*
Y531496D03*
G54D41*
X596457Y116142D03*
X374016Y156221D03*
G54D47*
X116066Y39074D03*
%LPC*%
G75*
G36*
G01X82399Y150340D02*
X71449Y139390D01*
X71358Y139396D01*
G03X70429Y139263I-160J-2196D01*
G01X70395Y139250D01*
X21301D01*
X19420Y141131D01*
Y250849D01*
X21091Y252520D01*
X93559D01*
X97030Y249049D01*
Y153951D01*
X93419Y150340D01*
X82399D01*
G37*
%LPD*%
G75*
G54D16*
X37402Y517441D03*
X789370D03*
G54D13*
X22550Y156750D03*
X54697Y165269D03*
X58697D03*
X59600Y152000D03*
X71200Y137200D03*
X52400Y237800D03*
X28455Y187767D03*
X28749Y191548D03*
X39301Y203166D03*
X33700Y230600D03*
X21910Y217500D03*
X22250Y223500D03*
X46194Y179835D03*
X50194D03*
X39320Y213823D03*
X64000Y178400D03*
X72800Y178200D03*
X22150Y203550D03*
X26150Y230850D03*
X23100Y283200D03*
X22750Y275450D03*
X23500Y296700D03*
X68300Y292200D03*
X45650Y250280D03*
X49320D03*
X40290Y239814D03*
X35405Y239808D03*
X32469Y250280D03*
X37469D03*
X52450Y333850D03*
X31450Y334050D03*
X74150Y334250D03*
X28000Y326500D03*
X24000Y301750D03*
X23400Y309500D03*
X67800Y318000D03*
X67700Y321500D03*
X58900Y334180D03*
X62325Y334068D03*
X37900Y334380D03*
X41325Y334268D03*
X65500Y378800D03*
X43000Y378233D03*
X22000Y378352D03*
X53500Y403150D03*
X49700Y402000D03*
X50700Y378233D03*
X54800Y373600D03*
X29900Y378252D03*
X38200Y373800D03*
X34100D03*
X73100Y378700D03*
X60400Y373600D03*
X77200Y374000D03*
X65375Y392835D03*
X35800Y363400D03*
X40100D03*
X92300Y194900D03*
X78800Y205900D03*
X92300Y213900D03*
X89800Y178000D03*
X80688Y281695D03*
Y276695D03*
X93884Y242333D03*
X102300Y329100D03*
X95245Y334043D03*
X80700Y309400D03*
X80600Y304600D03*
Y334580D03*
X84025Y334468D03*
X102400Y333900D03*
X106500D03*
X85795Y378426D03*
X102395Y373793D03*
X93695Y378426D03*
X81300Y374000D03*
X98295Y373793D03*
X106709Y383400D03*
X112023Y383013D03*
X78171Y363195D03*
X82171D03*
X99266Y362988D03*
X103266D03*
X104900Y412200D03*
X102679Y391150D03*
X112638Y391197D03*
X107582Y391266D03*
X182100Y105500D03*
X155991Y110061D03*
X200550Y111350D03*
X152800Y113400D03*
X164020Y101127D03*
X158612Y126645D03*
X198202Y135298D03*
X201139Y121630D03*
X172800Y141001D03*
X180300Y175400D03*
X145585Y132451D03*
X197100Y298800D03*
X162522Y331774D03*
X196600Y306800D03*
X250137Y36053D03*
X261499Y55353D03*
X257499D03*
X241750Y98250D03*
X238867Y63650D03*
X255300Y72600D03*
X234693Y57400D03*
X255154Y69177D03*
X233759Y64752D03*
X220228Y63651D03*
X204400Y288700D03*
X248900Y282932D03*
X259629Y281000D03*
X242351Y282900D03*
X228300Y280900D03*
X219400Y279400D03*
X262800Y277835D03*
X242400Y289700D03*
X242402Y286300D03*
X225500Y278900D03*
X222320Y277658D03*
X207500Y278400D03*
X204997Y280702D03*
X222000Y310600D03*
X231700Y320100D03*
X249775Y320167D03*
X214700Y320200D03*
X212198Y328316D03*
X208648Y328452D03*
X261365Y324351D03*
X245943Y326300D03*
X246100Y329700D03*
X230400Y326200D03*
Y329600D03*
X253245Y329698D03*
X253154Y326227D03*
X241556Y340111D03*
X237483Y339988D03*
X230000Y336500D03*
X233400Y336600D03*
X218400Y326600D03*
X218300Y330000D03*
X230400Y348000D03*
X255500Y423361D03*
X256172Y409530D03*
X261996Y365663D03*
X263250Y423411D03*
X257996Y365663D03*
X259800Y423400D03*
X256900Y380900D03*
X281700Y52285D03*
X285500D03*
X308591Y68928D03*
X304591D03*
X308591Y73074D03*
X311182Y58692D03*
X276700Y66700D03*
X283385Y100227D03*
X287385D03*
X319533Y114283D03*
X291385Y100227D03*
X295385D03*
X306196Y110209D03*
X310711Y113820D03*
X314772Y108292D03*
X300311Y60800D03*
X300385Y108227D03*
X311182Y62800D03*
X272937Y90362D03*
X266895Y100227D03*
X306280Y82574D03*
X283393Y92325D03*
X301280Y82574D03*
X272937Y85862D03*
X304591Y73074D03*
X318773Y108083D03*
X278039Y82185D03*
X279385Y100227D03*
X292030Y90574D03*
X292385Y108227D03*
X280298Y95556D03*
X296280Y82574D03*
X324026Y115936D03*
X321343Y122343D03*
X321051Y134028D03*
X304529Y118792D03*
X317600Y278800D03*
X319543Y290159D03*
X303032Y289900D03*
X268400Y281000D03*
X266406Y277835D03*
X306292Y252825D03*
X302262Y262642D03*
X299635Y288650D03*
X292225Y288267D03*
X297021Y346579D03*
X287350Y351200D03*
X319550Y347169D03*
X305147Y354706D03*
X316050Y342200D03*
X287350Y357700D03*
X322500Y353700D03*
X301500Y337500D03*
X320650Y336456D03*
X306060Y337640D03*
X310200Y337600D03*
X280800Y325000D03*
X290750D03*
X280217Y350927D03*
X269365Y320351D03*
X325500Y325400D03*
X314241Y308459D03*
X314300Y311900D03*
X308180Y305200D03*
X305628Y320511D03*
X301628D03*
X325500Y321400D03*
X314400Y327851D03*
X314045Y302900D03*
X314500Y324251D03*
X319100Y330600D03*
X305628Y324511D03*
X324100Y307814D03*
X265365Y324351D03*
X281150Y332000D03*
X288536Y314764D03*
X275696Y314340D03*
X308398Y386479D03*
X304205Y382450D03*
X304398Y386479D03*
X292800Y363800D03*
X300019Y379524D03*
X296079D03*
X325200Y365100D03*
X312398Y386479D03*
X270618Y385867D03*
X268004Y424361D03*
X323448Y405064D03*
X266500Y364000D03*
X325629Y443510D03*
X328600Y114400D03*
X328711Y108053D03*
X335722Y94574D03*
X329722D03*
X374616Y172378D03*
X370061Y172433D03*
X355500Y144500D03*
X342000Y141600D03*
X331649Y126111D03*
X339049Y124238D03*
X335994Y126119D03*
X341913Y145049D03*
X374915Y176442D03*
X359969Y124510D03*
X349911Y136954D03*
X357546Y230354D03*
X360710Y231897D03*
X376306Y182715D03*
X351723Y178499D03*
X354143Y183439D03*
X362260Y184360D03*
X364169Y188366D03*
X366460Y191794D03*
X368558Y194540D03*
X379415Y194608D03*
X370570Y198219D03*
X371124Y178760D03*
X372517Y182362D03*
X380400Y287400D03*
X382000Y296500D03*
X384600Y285600D03*
X379000Y272600D03*
X384300Y291100D03*
X346900Y281300D03*
X343100D03*
X357996Y272841D03*
X328134Y252720D03*
X332000Y266336D03*
X376633Y261543D03*
X340280Y253765D03*
X337500Y266050D03*
X358096Y262268D03*
X341998Y256700D03*
X368610Y257299D03*
X376633Y256851D03*
X385887Y305222D03*
X381396Y302610D03*
X335400Y337400D03*
X345700Y349773D03*
X337600Y349600D03*
X339000Y344700D03*
X330000Y345800D03*
X335882Y309823D03*
X327400Y342600D03*
X386159Y337080D03*
X375148Y337184D03*
X382600Y337200D03*
X344000Y316000D03*
X346500Y302500D03*
X356550Y337200D03*
X348596Y337250D03*
X347750Y315850D03*
X352396Y337200D03*
X331026Y303354D03*
X328100Y331300D03*
X329364Y316949D03*
X364050Y337200D03*
X374250Y347600D03*
X359200Y315800D03*
X355200D03*
X360300Y323900D03*
X363400Y315800D03*
X344000Y388500D03*
X340375Y365944D03*
X331765Y386535D03*
X367450Y409955D03*
X338000Y421000D03*
X367350Y406455D03*
X360000Y410000D03*
X337592Y405027D03*
X448300Y337500D03*
X444100Y341000D03*
X444200Y337600D03*
X444100Y345000D03*
X440300Y337500D03*
X416822Y347133D03*
X412381Y347149D03*
X435000Y347800D03*
X441000D03*
X433500Y337500D03*
X426464Y347078D03*
X397000Y337000D03*
X401700Y337350D03*
X392959Y337099D03*
X405921Y347159D03*
X430464Y347078D03*
X390550Y326820D03*
X405783Y339318D03*
X448500Y424000D03*
X445000Y422000D03*
X452300Y337500D03*
X468300D03*
X456550D03*
X464300D03*
X460800Y337562D03*
X460300Y333500D03*
X502138Y348500D03*
X476500Y347650D03*
X498138Y348500D03*
X506200Y358809D03*
X493200Y358800D03*
X498700Y359209D03*
X452600Y332700D03*
X462450Y358960D03*
X472463Y329837D03*
X468500Y347500D03*
X476200Y334900D03*
X506262Y348500D03*
X510138D03*
X479640Y334674D03*
X503800Y382700D03*
X473900Y371800D03*
X485100Y363400D03*
X510200Y363209D03*
X506200D03*
X494400Y363800D03*
X499100Y363409D03*
X452500Y423500D03*
X510700Y367309D03*
X506700D03*
X489600Y367209D03*
X474200Y367500D03*
X457599Y419642D03*
X496300Y378935D03*
X489500Y371200D03*
X546627Y324049D03*
X551127D03*
X545278Y315738D03*
X549778D03*
X545221Y308771D03*
X549721D03*
X545193Y301280D03*
X549693D03*
X552200Y339300D03*
X556800D03*
X547225Y357997D03*
X547379Y338352D03*
X539900Y338300D03*
X534000Y338400D03*
X538225Y357997D03*
X555697Y356565D03*
X514000Y359209D03*
X514138Y348500D03*
X518138Y348350D03*
X525438Y350500D03*
X519263Y327092D03*
X538476Y334365D03*
X538436Y330918D03*
X534100Y342410D03*
X536200Y348300D03*
X540200D03*
X550100D03*
X546100D03*
X554685Y333410D03*
X547927Y342199D03*
X543646Y342347D03*
X539446D03*
X519629Y330448D03*
X521914Y332907D03*
X574250Y466900D03*
X545880Y485940D03*
X539040Y480090D03*
X562460Y457580D03*
X632416Y31609D03*
X627603Y43523D03*
X627500Y19339D03*
X626786Y31227D03*
X634400Y102000D03*
X630600D03*
X627500Y64500D03*
X629500Y61500D03*
X635852Y133715D03*
X636363Y209944D03*
X632363D03*
X628363D03*
X624363D03*
X622400Y216750D03*
X594025Y280017D03*
X631800Y316137D03*
X603650Y315500D03*
X594292Y362291D03*
X625000Y361700D03*
X590350Y323011D03*
X629250Y310491D03*
Y306491D03*
X626405Y314991D03*
X629250Y344900D03*
Y348900D03*
X623063Y357337D03*
X602649Y349033D03*
X594400Y357000D03*
Y353000D03*
X597450Y324750D03*
Y320750D03*
X584280Y424030D03*
X598023Y383081D03*
X624200Y372500D03*
X620260Y389940D03*
X589394Y384572D03*
X589391Y378202D03*
X627140Y381353D03*
X631140D03*
X594200Y395200D03*
X604832Y395220D03*
X581020Y471890D03*
X574667Y479799D03*
X577300Y460300D03*
X588400Y469450D03*
X634050Y469200D03*
X588663Y460037D03*
X581250Y480550D03*
X585420Y456480D03*
X633676Y460080D03*
X617000Y468700D03*
X588030Y430795D03*
X620600Y458500D03*
X656300Y20100D03*
X660200Y20200D03*
X647216Y31601D03*
X667900Y40800D03*
X643816Y31573D03*
X640144Y40969D03*
X643103Y13803D03*
X664301Y40104D03*
Y49998D03*
X638103Y13100D03*
X640416Y31609D03*
X647103Y13964D03*
X694365Y94458D03*
Y90958D03*
X686279Y94494D03*
Y90994D03*
X678225Y94496D03*
Y90996D03*
X670146Y94505D03*
Y91005D03*
X662047Y94539D03*
Y91039D03*
X654037Y94708D03*
Y91208D03*
X668100Y56100D03*
X651564Y52638D03*
X644500Y65759D03*
X657480Y113385D03*
X678189Y108784D03*
X689049Y109487D03*
X669500Y108400D03*
X640600Y111600D03*
X641003Y68809D03*
X660629Y170078D03*
Y173227D03*
X654330Y157480D03*
X651181Y154330D03*
X673229Y170079D03*
X679527Y173229D03*
X692126Y141732D03*
X698425D03*
X679527Y148031D03*
X685826D03*
X692126D03*
X698425D03*
X679527Y154330D03*
X685826D03*
X692126D03*
X698425D03*
Y160629D03*
X692126D03*
X685826D03*
X679527D03*
X698425Y166929D03*
X692126D03*
X685826D03*
X679527D03*
X698425Y173228D03*
X692126D03*
X685826D03*
X670078Y170078D03*
X654330Y173228D03*
X651181Y166929D03*
X676376Y132281D03*
X666929Y129134D03*
X660630Y160630D03*
X640775Y156218D03*
X648031Y157480D03*
X663779Y151181D03*
X666929Y148031D03*
X663779Y132283D03*
X663778Y144883D03*
Y138584D03*
X651181Y141732D03*
Y132283D03*
Y122834D03*
X644882Y154331D03*
X637952Y142515D03*
X640500Y125000D03*
X660629Y144883D03*
X657481Y132284D03*
X670078Y151181D03*
X637343Y171335D03*
Y174835D03*
X657480Y154330D03*
X644882Y173228D03*
Y176378D03*
Y170078D03*
X648031D03*
X670078Y157480D03*
X673228Y148031D03*
X692126Y125984D03*
X685827Y116535D03*
X670079Y125985D03*
X682678D03*
X676378D03*
X688977D03*
X676378Y119686D03*
X666929Y119685D03*
X663780Y125985D03*
X657479Y116536D03*
X654330Y116535D03*
Y119685D03*
Y122834D03*
X657480Y125984D03*
X654331D03*
X654330Y129134D03*
Y132283D03*
Y135433D03*
X651181D03*
X654330Y138582D03*
Y141732D03*
Y144882D03*
X651181D03*
X654330Y148031D03*
Y151181D03*
X679452Y209815D03*
X683913Y213313D03*
X695275Y198425D03*
X692125Y198423D03*
X686352Y207200D03*
X651181Y192125D03*
X663779D03*
X657480D03*
X670078D03*
X654330Y185826D03*
Y179526D03*
X685826Y192125D03*
X692125D03*
X667353Y233486D03*
X640363Y209944D03*
X638479Y230640D03*
X674023Y213815D03*
X640509Y177600D03*
X674172Y210095D03*
X679400Y213300D03*
X679527Y198424D03*
X697149Y219742D03*
X692949D03*
X695383Y266855D03*
X644153Y278745D03*
X660400Y271900D03*
X678500Y240324D03*
X691100Y240354D03*
X686900D03*
X668600Y242800D03*
X669450Y284900D03*
X695600Y244354D03*
X695375Y260875D03*
X637500Y362400D03*
X680300Y384900D03*
X674150Y415380D03*
X654770Y401166D03*
X645970Y399130D03*
X669031Y388383D03*
X665031D03*
X653360Y386210D03*
X680700Y378200D03*
X687150Y385550D03*
X675031Y389383D03*
X653007Y382828D03*
X658601Y401800D03*
X673900Y418880D03*
X637500Y365900D03*
X692200Y428700D03*
X681540Y429640D03*
X678700Y440950D03*
X671640Y454410D03*
X683250Y437813D03*
X710378Y96399D03*
Y92899D03*
X702391Y94510D03*
Y91010D03*
X722673Y105444D03*
X736785Y110185D03*
X737800Y106525D03*
X717197Y109646D03*
X726100Y107200D03*
X734709Y106595D03*
X731000Y106315D03*
X734212Y109995D03*
X725943Y100147D03*
X744833Y78995D03*
X754572Y86923D03*
X754528Y83228D03*
X745100Y97500D03*
X699563Y108815D03*
X719010Y107281D03*
X707649Y110002D03*
X710517Y106823D03*
X750773Y74636D03*
X747919Y76667D03*
X720744Y92427D03*
X704849Y107385D03*
X729921Y157480D03*
X739952Y120649D03*
X740952Y126815D03*
X707874Y116535D03*
X743100Y114700D03*
X737352Y145885D03*
X726771Y122835D03*
X729921Y122834D03*
X737702Y128565D03*
X729921Y132283D03*
Y129134D03*
X711023Y116535D03*
X726771Y163779D03*
X741754Y134617D03*
X729921Y135433D03*
X739622Y137008D03*
X729921Y138582D03*
Y144882D03*
X714173Y116535D03*
X717322D03*
X707873Y129133D03*
X720473Y116536D03*
X704725D03*
X704724Y148031D03*
Y154330D03*
Y160629D03*
Y166929D03*
Y173228D03*
X714173Y122834D03*
X720472D03*
X741077Y159790D03*
X757471Y148193D03*
X723621Y148031D03*
Y154330D03*
Y160629D03*
Y166929D03*
Y173228D03*
X707874Y122835D03*
X723621Y135433D03*
Y129133D03*
Y141732D03*
X701575Y122835D03*
X714173Y141732D03*
X723622Y116535D03*
X704723Y129133D03*
X701574D03*
X711022D03*
X714172D03*
X729921Y125984D03*
X711023Y173228D03*
X741952Y173115D03*
X738352Y174615D03*
X729920Y176378D03*
Y173229D03*
X736219Y170079D03*
X733070D03*
X746750Y157700D03*
X729921Y148031D03*
Y141732D03*
Y163779D03*
X750550Y135200D03*
X729921Y160629D03*
X701575Y116536D03*
X729921Y154330D03*
X730737Y235199D03*
X724465Y224741D03*
X714620Y221041D03*
X743460Y231900D03*
X701574Y192125D03*
X707873D03*
X714173D03*
X723621D03*
Y185826D03*
Y179527D03*
X715467Y210507D03*
X725009Y213292D03*
X739852Y195915D03*
X737832Y202664D03*
X729920Y188977D03*
X739752Y199615D03*
X738416Y190551D03*
X729920Y182678D03*
X745485Y197673D03*
Y201673D03*
X740352Y180115D03*
X729920Y185827D03*
X724776Y209963D03*
X743752Y187115D03*
X742502Y182715D03*
X742252Y177015D03*
X737315Y177952D03*
X733070Y179527D03*
X720819Y209800D03*
X729246Y209941D03*
X736272Y208181D03*
X729136Y206654D03*
X738839Y206080D03*
X733565Y210184D03*
X729920Y192126D03*
X720357Y207104D03*
X714173Y198425D03*
X729921Y179527D03*
X720471Y198424D03*
X731915Y206310D03*
X738952Y184215D03*
X744052Y193784D03*
X701574Y198424D03*
X711023Y198425D03*
X704724D03*
X717322D03*
X707873Y198424D03*
X723621D03*
X704724Y201574D03*
X706737Y205505D03*
X705336Y208437D03*
X711310Y207023D03*
X714173Y201574D03*
X718330Y205172D03*
X704708Y264647D03*
X749620Y273620D03*
X707574Y276558D03*
X712720Y240976D03*
X754227Y297611D03*
X739300Y287611D03*
X751693Y255540D03*
X743507Y251685D03*
X747558Y247274D03*
X759558Y241027D03*
Y247274D03*
X731300Y287611D03*
X735300D03*
X731318Y283571D03*
X735318D03*
X731155Y279636D03*
X739318Y283571D03*
X734638Y275696D03*
X751693Y259540D03*
X755693D03*
X704708Y256647D03*
Y252647D03*
X753560Y273780D03*
X704708Y260647D03*
X721380Y423930D03*
X739680Y423900D03*
X700200Y388200D03*
Y384800D03*
X743480Y439080D03*
X710200Y441200D03*
X706120Y441410D03*
X729870Y451300D03*
X740900Y456400D03*
X700855Y426719D03*
X761650Y89937D03*
X771610Y93040D03*
X799500Y106000D03*
X781000Y88000D03*
Y84200D03*
X788287Y86087D03*
X768250Y106300D03*
X768100Y109700D03*
X763560Y59820D03*
X767359Y82076D03*
X804320Y134300D03*
X804400Y175000D03*
X760800Y169550D03*
X769600Y164200D03*
X765200Y135750D03*
X786500Y134283D03*
X763050Y154100D03*
X761400Y160050D03*
X764600Y141500D03*
X768700Y129800D03*
X768900Y134800D03*
X760715Y197200D03*
X764550Y182900D03*
X764750Y179300D03*
X761550Y180500D03*
X786400Y179000D03*
X779200Y178650D03*
X790714Y237308D03*
X801618Y210116D03*
Y214116D03*
X786006Y283383D03*
X775486Y287316D03*
X781640Y282160D03*
X793837Y291696D03*
X805254Y263886D03*
X761484Y255581D03*
Y251581D03*
X780837Y240885D03*
X774637Y267746D03*
X770637D03*
X761638Y259635D03*
X774637Y259746D03*
Y263746D03*
X793837Y279636D03*
Y275696D03*
X780837Y267826D03*
X784837Y263891D03*
Y259951D03*
X793852Y256011D03*
Y252076D03*
X793837Y271761D03*
Y267826D03*
Y263696D03*
X774657Y255999D03*
X765638Y255635D03*
X774637Y251876D03*
X784837Y271761D03*
Y267826D03*
X793837Y287696D03*
X780837Y271761D03*
X801853Y300515D03*
X767890Y273380D03*
X763292Y287630D03*
X765764Y326844D03*
X801728Y304572D03*
X776497Y338392D03*
X775672Y350204D03*
X782770Y321200D03*
G54D14*
X38502Y161319D03*
X49302D03*
X43902D03*
X49302Y150519D03*
Y155919D03*
X43902Y150519D03*
Y155919D03*
X38502D03*
Y150519D03*
X108672Y138471D03*
Y132871D03*
X90672Y138471D03*
X102672D03*
X96672D03*
X84672D03*
Y132871D03*
X96672D03*
X102672D03*
X90672D03*
G54D23*
X98425Y472441D03*
X137795D03*
G54D30*
X388189Y44095D03*
X374016D03*
X359843D03*
X345670D03*
X388189Y38583D03*
X374016D03*
X359843D03*
X345670D03*
X388189Y29922D03*
X374016D03*
X359843D03*
X345670D03*
X388189Y24410D03*
X374016D03*
X359843D03*
X345670D03*
X388189Y15748D03*
X374016D03*
X359843D03*
X345670D03*
X388189Y10237D03*
X374016D03*
X359843D03*
X345670D03*
X381103Y48819D03*
X366929D03*
X352756D03*
X338583D03*
X381103Y43307D03*
X366929D03*
X352756D03*
X338583D03*
X381103Y34646D03*
X366929D03*
X352756D03*
X338583D03*
X381103Y29134D03*
X366929D03*
X352756D03*
X338583D03*
X381103Y20473D03*
X366929D03*
X352756D03*
X338583D03*
X381103Y14961D03*
X366929D03*
X352756D03*
X338583D03*
X444882Y44095D03*
X430709D03*
X416536D03*
X402363D03*
X444882Y38583D03*
X430709D03*
X416536D03*
X402363D03*
X444882Y29922D03*
X430709D03*
X416536D03*
X402363D03*
X444882Y24410D03*
X430709D03*
X416536D03*
X402363D03*
X444882Y15748D03*
X430709D03*
X416536D03*
X402363D03*
X444882Y10237D03*
X430709D03*
X416536D03*
X402363D03*
X437796Y48819D03*
X423622D03*
X409449D03*
X395276D03*
X437796Y43307D03*
X423622D03*
X409449D03*
X395276D03*
X437796Y34646D03*
X423622D03*
X409449D03*
X395276D03*
X437796Y29134D03*
X423622D03*
X409449D03*
X395276D03*
X437796Y20473D03*
X423622D03*
X409449D03*
X395276D03*
X437796Y14961D03*
X423622D03*
X409449D03*
X395276D03*
X404528Y412795D03*
X413386D03*
X422244D03*
X407480Y422244D03*
X416339D03*
X425197D03*
X407480Y407284D03*
X416339D03*
X425197D03*
X404528Y427756D03*
X413386D03*
X422244D03*
X404528Y442717D03*
X413386D03*
X422244D03*
X404528Y457677D03*
X413386D03*
X422244D03*
X407480Y437205D03*
X416339D03*
X425197D03*
X407480Y452165D03*
X416339D03*
X425197D03*
X501575Y44095D03*
X487402D03*
X473229D03*
X459055D03*
X501575Y38583D03*
X487402D03*
X473229D03*
X459055D03*
X501575Y29922D03*
X487402D03*
X473229D03*
X459055D03*
X501575Y24410D03*
X487402D03*
X473229D03*
X459055D03*
X501575Y15748D03*
X487402D03*
X473229D03*
X459055D03*
X501575Y10237D03*
X487402D03*
X473229D03*
X459055D03*
X508662Y48819D03*
X494489D03*
X480315D03*
X466142D03*
X451969D03*
X508662Y43307D03*
X494489D03*
X480315D03*
X466142D03*
X451969D03*
X508662Y34646D03*
X494489D03*
X480315D03*
X466142D03*
X451969D03*
X508662Y29134D03*
X494489D03*
X480315D03*
X466142D03*
X451969D03*
X508662Y20473D03*
X494489D03*
X480315D03*
X466142D03*
X451969D03*
X508662Y14961D03*
X494489D03*
X480315D03*
X466142D03*
X451969D03*
X572441Y44095D03*
X558268D03*
X544095D03*
X529922D03*
X515748D03*
X572441Y38583D03*
X558268D03*
X544095D03*
X529922D03*
X515748D03*
X572441Y29922D03*
X558268D03*
X544095D03*
X529922D03*
X515748D03*
X572441Y24410D03*
X558268D03*
X544095D03*
X529922D03*
X515748D03*
X572441Y15748D03*
X558268D03*
X544095D03*
X529922D03*
X515748D03*
X572441Y10237D03*
X558268D03*
X544095D03*
X529922D03*
X515748D03*
X565355Y48819D03*
X551181D03*
X537008D03*
X522835D03*
X565355Y43307D03*
X551181D03*
X537008D03*
X522835D03*
X565355Y34646D03*
X551181D03*
X537008D03*
X522835D03*
X565355Y29134D03*
X551181D03*
X537008D03*
X522835D03*
X565355Y20473D03*
X551181D03*
X537008D03*
X522835D03*
X565355Y14961D03*
X551181D03*
X537008D03*
X522835D03*
X586614Y44095D03*
Y38583D03*
Y29922D03*
Y24410D03*
Y15748D03*
Y10237D03*
X579528Y48819D03*
Y43307D03*
Y34646D03*
Y29134D03*
Y20473D03*
Y14961D03*
X758267Y44095D03*
X744094D03*
X729921D03*
X715748D03*
X758267Y38583D03*
X744094D03*
X729921D03*
X715748D03*
X758267Y29922D03*
X744094D03*
X729921D03*
X715748D03*
X758267Y24410D03*
X744094D03*
X729921D03*
X715748D03*
X758267Y15748D03*
X744094D03*
X729921D03*
X715748D03*
X758267Y10237D03*
X744094D03*
X729921D03*
X715748D03*
X751181Y48819D03*
X737007D03*
X722834D03*
X708661D03*
X751181Y43307D03*
X737007D03*
X722834D03*
X708661D03*
X751181Y34646D03*
X737007D03*
X722834D03*
X708661D03*
X751181Y29134D03*
X737007D03*
X722834D03*
X708661D03*
X751181Y20473D03*
X737007D03*
X722834D03*
X708661D03*
X751181Y14961D03*
X737007D03*
X722834D03*
X708661D03*
G54D21*
X128580Y170810D03*
X122984Y170984D03*
X123200Y175800D03*
X125741Y166309D03*
X128459Y175658D03*
X94080Y448470D03*
X198557Y153196D03*
X177850Y324800D03*
X174995Y353588D03*
Y358388D03*
X165195D03*
X169995D03*
Y353588D03*
X197718Y350937D03*
Y355859D03*
X177468Y417900D03*
X142865Y424021D03*
X143608Y415900D03*
X158067Y378857D03*
X176311Y445493D03*
X176423Y440472D03*
X177421Y432909D03*
X177532Y426134D03*
X145392Y445207D03*
X145456Y440338D03*
X142991Y430900D03*
X253600Y139500D03*
Y134700D03*
X251800Y153600D03*
Y144000D03*
Y148800D03*
X258400Y134700D03*
Y139500D03*
X263200Y134700D03*
Y139500D03*
X253600Y230500D03*
Y225700D03*
Y220900D03*
X258400Y230500D03*
Y225700D03*
Y220900D03*
X263200Y230500D03*
Y225700D03*
Y220900D03*
X249204Y244103D03*
X254300Y357732D03*
X246700Y418600D03*
X212589Y494694D03*
X220589D03*
X216589Y489694D03*
X208589D03*
X224589D03*
X295960Y148987D03*
Y154387D03*
X308907Y171800D03*
Y166400D03*
Y161000D03*
X272800Y168000D03*
Y172800D03*
Y134700D03*
X268000Y165962D03*
X268064Y171792D03*
X268000Y158700D03*
Y153900D03*
Y134700D03*
Y139500D03*
Y144300D03*
Y149100D03*
X296200Y195900D03*
Y190500D03*
X308907Y215200D03*
Y220600D03*
Y226000D03*
Y231400D03*
Y236800D03*
Y209800D03*
Y188200D03*
Y199000D03*
Y204400D03*
Y177200D03*
Y193600D03*
Y182800D03*
X296400Y237950D03*
Y232550D03*
X272800Y177600D03*
X268064Y184062D03*
X268000Y235300D03*
Y230500D03*
Y225700D03*
Y220900D03*
Y216000D03*
Y211200D03*
X268118Y191305D03*
X268000Y206400D03*
Y196800D03*
Y201600D03*
Y178062D03*
X308907Y242200D03*
X266404Y249707D03*
X268000Y244900D03*
Y240100D03*
X276070Y395357D03*
X346700Y296333D03*
Y291533D03*
X490877Y185047D03*
Y180547D03*
X510427Y184931D03*
Y180431D03*
X500302Y184989D03*
Y180489D03*
X553500Y231900D03*
X549000D03*
X520552Y184873D03*
Y180373D03*
X550717Y255796D03*
X546217D03*
X550975Y248209D03*
X546475D03*
X551865Y240638D03*
X547365D03*
X570234Y298026D03*
X572634Y293526D03*
X567200Y407700D03*
X572062Y384378D03*
X529500Y471500D03*
X551400Y437800D03*
X545900D03*
X539800Y437900D03*
X576797Y113877D03*
X589706Y174031D03*
X586081Y158407D03*
X585145Y162809D03*
X595402Y149579D03*
X594466Y153981D03*
X588070Y138220D03*
X587134Y142622D03*
X576868Y127381D03*
X575932Y131783D03*
X582554Y116361D03*
X589135Y214107D03*
X588199Y218509D03*
X585010Y198483D03*
X584074Y202885D03*
X580885Y182859D03*
X579949Y187261D03*
X588770Y178433D03*
X575134Y298026D03*
X577534Y293526D03*
X580034Y298026D03*
X632150Y389100D03*
X576862Y384378D03*
X581087Y379569D03*
X576287D03*
X581692Y384378D03*
X605534Y480027D03*
X635000Y427784D03*
X619600Y446100D03*
X629200D03*
X624400D03*
X655964Y52248D03*
X675136Y268500D03*
X637705Y298765D03*
X642705D03*
X696900Y337800D03*
X697500Y358200D03*
X637705Y303765D03*
X642705D03*
X674700Y306300D03*
X679500D03*
Y311100D03*
X674700D03*
X679500Y315900D03*
X674700D03*
X665520Y307707D03*
Y312507D03*
X654642D03*
X654488Y317417D03*
X660100Y307500D03*
X654642Y307707D03*
X665478Y317527D03*
X684400Y400100D03*
X637550Y389050D03*
X655532Y425245D03*
X658032Y420245D03*
X653032D03*
X653200Y408800D03*
X688500Y484400D03*
X675700Y468000D03*
Y463500D03*
X675400Y472300D03*
X659000Y428900D03*
X652200Y429100D03*
X639120Y462230D03*
X688500Y488600D03*
X714600Y338900D03*
Y348500D03*
Y343700D03*
X709800Y348500D03*
Y343700D03*
X706500Y337800D03*
X701700D03*
X707100Y358200D03*
X702300D03*
X722100Y368300D03*
X717300D03*
X712500D03*
X742200Y380400D03*
Y370800D03*
Y375600D03*
X728700Y381000D03*
Y376200D03*
Y371400D03*
X722100Y363500D03*
X717300D03*
X712500D03*
X705900Y386900D03*
X711000Y395100D03*
X710900Y386800D03*
X706000Y395100D03*
X740900Y476400D03*
Y469400D03*
Y461900D03*
X704340Y468062D03*
X705400Y477400D03*
X771083Y211784D03*
G54D32*
X374432Y316002D03*
X425197Y236220D03*
X425196Y228347D03*
X433070Y236221D03*
X440944D03*
X448818D03*
X433070Y228347D03*
X440944D03*
X448818D03*
X405512Y212599D03*
X393701Y208662D03*
X401575D03*
X409449D03*
X417323D03*
X425197D03*
X433071D03*
X440945D03*
X448819D03*
X413386Y212599D03*
X421260D03*
X429134D03*
X437008D03*
X444882D03*
X409449Y232284D03*
X397638Y236221D03*
Y228347D03*
Y224410D03*
X389000Y236100D03*
X401575Y236221D03*
X405512D03*
X417322D03*
X409449Y220473D03*
Y216536D03*
X413386Y220473D03*
Y216536D03*
X417323Y220473D03*
Y216536D03*
X421260Y220473D03*
Y216536D03*
X425197Y220473D03*
Y216536D03*
X429134Y220473D03*
Y216536D03*
X433071Y220473D03*
Y216536D03*
X437008Y220473D03*
Y216536D03*
X440945Y220473D03*
Y216536D03*
X444882Y220473D03*
Y216536D03*
X448819Y220473D03*
Y216536D03*
X409449Y204725D03*
Y200788D03*
X413386Y208662D03*
Y204725D03*
X417323D03*
Y200788D03*
X421260Y208662D03*
Y204725D03*
X425197D03*
Y200788D03*
X429134Y208662D03*
Y204725D03*
X433071D03*
Y200788D03*
X437008Y208662D03*
Y204725D03*
X440945D03*
Y200788D03*
X444882Y208662D03*
Y204725D03*
X448819D03*
Y200788D03*
X389764Y216536D03*
Y212599D03*
X397638Y220473D03*
Y216536D03*
X401575Y220473D03*
Y216536D03*
X405512Y220473D03*
Y216536D03*
X393701Y204725D03*
Y200788D03*
X397638Y208662D03*
Y204725D03*
X401575D03*
Y200788D03*
X405512Y208662D03*
Y204725D03*
X401575Y232284D03*
X401727Y228641D03*
X405512Y232284D03*
X413386D03*
X405512Y228347D03*
X409449Y259843D03*
X425197Y291339D03*
X433071Y295276D03*
Y299213D03*
Y291339D03*
X448819Y287403D03*
X448818Y291339D03*
Y295276D03*
X437008Y299213D03*
Y291339D03*
X429134Y295277D03*
Y299214D03*
X437007Y287402D03*
X429134Y291340D03*
X437008Y275591D03*
X444882D03*
X437007Y267718D03*
X448818Y255906D03*
Y263780D03*
Y271655D03*
X440944Y263780D03*
Y271655D03*
X437007Y259843D03*
Y255905D03*
X440944Y255906D03*
X421260Y259843D03*
X429134Y263781D03*
Y255906D03*
X433071Y283465D03*
X425197Y287402D03*
X444882D03*
X440945Y283465D03*
X448819D03*
X444882Y299213D03*
X425196Y240158D03*
X409449D03*
Y248032D03*
X397638Y244095D03*
X421260Y255906D03*
X425197Y299213D03*
X429134Y287403D03*
X417323Y259843D03*
X413386Y255906D03*
X440945Y295276D03*
Y299213D03*
Y291339D03*
Y287402D03*
X437008Y295276D03*
X429134Y251969D03*
X417323D03*
X413386Y248032D03*
X405512D03*
X421260Y251969D03*
X405512Y244095D03*
X401575D03*
X413386D03*
X417323Y248032D03*
X401575Y240158D03*
X405512D03*
X433070Y287402D03*
X413387Y240158D03*
X421260Y248032D03*
X417323Y244095D03*
X413386Y251969D03*
X401575Y248032D03*
X421260Y295277D03*
X448819Y244095D03*
X440945D03*
X433071D03*
X421259Y240158D03*
X421260Y244095D03*
X417323Y240157D03*
X421260Y299214D03*
X425197Y295276D03*
X413386Y311025D03*
X425197Y318898D03*
Y303150D03*
X429134Y314961D03*
Y311024D03*
X448819Y307088D03*
X448818Y311024D03*
Y303151D03*
X444882Y314961D03*
Y318898D03*
X433071Y314961D03*
X431102Y331263D03*
X429134Y303151D03*
X425197Y314961D03*
X413386Y326772D03*
X425197Y307087D03*
X417323Y314961D03*
X433071Y307087D03*
X448819Y314961D03*
X440945D03*
X417323Y311024D03*
X429134Y318898D03*
X442800Y330300D03*
X446200Y327400D03*
X440945Y303150D03*
Y311024D03*
Y307087D03*
X444881Y322835D03*
X442913Y327204D03*
X440944Y322835D03*
X438976Y327204D03*
X437008Y318898D03*
Y314961D03*
Y311024D03*
Y303150D03*
Y307087D03*
X433071Y318898D03*
X421260Y326772D03*
X421259Y322835D03*
X421260Y318898D03*
Y314961D03*
X417322Y322835D03*
X413386Y314962D03*
X421260Y307088D03*
X433071Y303150D03*
X421260Y303151D03*
X456693Y236221D03*
X464567D03*
X472441D03*
X460630Y208662D03*
X468504D03*
X484252D03*
X476378D03*
X496063D03*
X456693Y212599D03*
X464567D03*
X503937Y216536D03*
X472441Y212599D03*
X480315D03*
X488189D03*
X507874D03*
Y236221D03*
X503937Y232284D03*
X507874Y228347D03*
X503937Y224410D03*
X507874Y220473D03*
X472441Y228347D03*
X464567D03*
X456693D03*
X480315D03*
X484252Y236221D03*
X488189Y232284D03*
X500000Y200788D03*
X503937D03*
X456693Y220473D03*
Y216536D03*
X460630Y220473D03*
Y216536D03*
X464567Y220473D03*
Y216536D03*
X468504Y220473D03*
Y216536D03*
X472441Y220473D03*
Y216536D03*
X476378Y220473D03*
Y216536D03*
X480315Y220473D03*
Y216536D03*
X484252Y220473D03*
Y216536D03*
X488189Y220473D03*
Y216536D03*
X500000Y208662D03*
X503937D03*
X496063Y212599D03*
X500000D03*
X496063Y216536D03*
X500000D03*
X496063Y220473D03*
X500000D03*
X496063Y224410D03*
X500000D03*
X496063Y228347D03*
X500000D03*
X496063Y232284D03*
X500000D03*
X496063Y236221D03*
X500000D03*
X456693Y208662D03*
Y204725D03*
X460630D03*
Y200788D03*
X464567Y208662D03*
Y204725D03*
X468504D03*
Y200788D03*
X472441Y208662D03*
Y204725D03*
X476378D03*
Y200788D03*
X480315Y208662D03*
Y204725D03*
X484252D03*
Y200788D03*
X488189Y208662D03*
Y204725D03*
X468504Y299214D03*
X472442Y287402D03*
X480315Y295276D03*
X484252Y295277D03*
X476378Y291339D03*
X452755Y287402D03*
Y291340D03*
Y295277D03*
X503937Y255906D03*
X507874Y251969D03*
X503937Y248032D03*
X507874Y244095D03*
X503937Y240158D03*
X507874Y271654D03*
X503937Y267717D03*
X507874Y259843D03*
Y287402D03*
X503937Y283465D03*
X507874Y279528D03*
X503937Y275591D03*
Y299213D03*
X507874Y295276D03*
X503937Y291339D03*
X492126Y287402D03*
X484252Y271654D03*
Y279528D03*
X488189Y267717D03*
Y275591D03*
X492126Y271654D03*
Y279528D03*
X488189Y283465D03*
X484252Y259843D03*
Y251969D03*
Y244095D03*
X492126Y259843D03*
Y251969D03*
Y244095D03*
X472441Y291339D03*
X464568Y287402D03*
X460630Y275592D03*
X464568D03*
X452756D03*
X456693Y255906D03*
X464567D03*
Y263780D03*
X456693D03*
X464567Y271655D03*
X456693D03*
X476379Y287402D03*
X472441Y299213D03*
X480315D03*
X488189D03*
X456693Y287402D03*
X460630Y283465D03*
X468504D03*
X468505Y287402D03*
X460631Y295277D03*
X456693Y299213D03*
X460630D03*
X480316Y287403D03*
X484252Y291340D03*
Y287402D03*
X488189Y295276D03*
X456694D03*
X496063Y255906D03*
X500000D03*
X496063Y259843D03*
X500000D03*
X496063Y267717D03*
X500000D03*
X496063Y240158D03*
X500000D03*
X496063Y244095D03*
X500000D03*
X496063Y271654D03*
X500000D03*
X496063Y248032D03*
X500000D03*
X496063Y251969D03*
X500000D03*
X496063Y275591D03*
X500000D03*
X496063Y279528D03*
X500000D03*
X496063Y283465D03*
X500000D03*
X496063Y287402D03*
X500000D03*
X507874Y255906D03*
X511811D03*
Y259843D03*
X507874Y267717D03*
X511811D03*
X507874Y240158D03*
X511811D03*
Y244095D03*
Y271654D03*
X507874Y248032D03*
X511811D03*
Y251969D03*
X507874Y275591D03*
X511811D03*
Y279528D03*
X507874Y283465D03*
X511811D03*
Y287402D03*
X480315Y291339D03*
X496063Y299213D03*
X500000D03*
X496063Y291339D03*
X500000D03*
X496063Y295276D03*
X500000D03*
X476378Y267717D03*
Y275591D03*
Y259843D03*
Y251969D03*
X472441Y244095D03*
X464567D03*
X456693D03*
Y291339D03*
X460630D03*
X500001Y314961D03*
X503937Y318898D03*
X488189Y307087D03*
X492126Y311024D03*
X460630Y307087D03*
X456693D03*
X460630Y311024D03*
X462599Y327204D03*
X456693Y311024D03*
Y314961D03*
X452755Y307087D03*
Y303150D03*
X456693Y318898D03*
X507874Y303150D03*
X484252D03*
X496063Y318898D03*
X488189Y311024D03*
X484252Y307087D03*
Y314961D03*
X476378D03*
X468504D03*
X507874D03*
X492126D03*
X500000Y311025D03*
X460630Y314961D03*
X496063D03*
X476378Y311024D03*
X472441Y307087D03*
X488189Y303150D03*
X500000Y307088D03*
X503937Y311024D03*
X468504Y303151D03*
X460630Y303150D03*
X464567Y303151D03*
X503937Y307087D03*
X507874Y311024D03*
X464567Y307088D03*
X468505D03*
X472441Y314961D03*
X492126Y307087D03*
X496063Y311024D03*
X464567Y311025D03*
Y318898D03*
X472441D03*
X496063Y303150D03*
X500000D03*
X470473Y327204D03*
X468504Y311024D03*
X488189Y322835D03*
X515748Y259843D03*
Y244095D03*
Y271654D03*
Y251969D03*
Y279528D03*
Y287402D03*
X516500Y313000D03*
X682675Y132281D03*
X688974D03*
X660630Y122834D03*
X660629Y119685D03*
X663779Y122834D03*
Y119685D03*
X670079Y122835D03*
X670078Y119685D03*
X673229Y122835D03*
X673228Y119685D03*
X679528Y122835D03*
X679527Y119685D03*
X682678Y122835D03*
X682677Y119685D03*
X688977Y122835D03*
X688976Y119685D03*
X692126Y122835D03*
Y119686D03*
G54D24*
X145669Y25708D03*
Y47362D03*
Y19803D03*
Y31614D03*
Y41456D03*
Y53267D03*
G54D22*
X140000Y204950D03*
X78600Y321700D03*
X78700Y317400D03*
X201400Y174400D03*
X192400D03*
X196900D03*
X179800Y133500D03*
X175800Y129500D03*
X179800D03*
X175800Y133500D03*
X170900Y160500D03*
X151500D03*
X156300D03*
X161100D03*
X165900D03*
X192400Y191600D03*
X196900D03*
X201400D03*
X192400Y187300D03*
X196900D03*
X201400D03*
Y178700D03*
X192400Y183000D03*
X196900D03*
X201400D03*
X192400Y178700D03*
X196900D03*
X151500Y205000D03*
X156300D03*
X161100D03*
X165900D03*
X170900D03*
X178450Y203150D03*
X144800Y204950D03*
X246493Y399567D03*
X242893D03*
X257020Y390670D03*
X253420D03*
X249820D03*
X246220D03*
X256120Y395170D03*
X243120D03*
X247620D03*
X251870D03*
X242620Y390670D03*
X260893Y399567D03*
X257293D03*
X260620Y390670D03*
Y395170D03*
X253693Y399567D03*
X250093D03*
X444882Y279529D03*
X490877Y176547D03*
X510427Y176431D03*
X500302Y176489D03*
X490877Y189047D03*
X510427Y188931D03*
X500302Y188989D03*
X452757Y279529D03*
X520552Y176373D03*
Y188873D03*
X571300Y414800D03*
X527742Y425481D03*
X522942D03*
X518142D03*
X527742Y432481D03*
X522942D03*
X518142D03*
X557411Y481025D03*
X631864Y51848D03*
X618250Y162081D03*
X580900Y414800D03*
X576100D03*
X628113Y428617D03*
X623313D03*
X618513D03*
X613713D03*
X694365Y98458D03*
Y86958D03*
X686279Y98494D03*
Y86994D03*
X678225Y98496D03*
Y86996D03*
X670146Y98505D03*
Y87005D03*
X662047Y98539D03*
Y87039D03*
X654037Y98708D03*
Y87208D03*
X670080Y148030D03*
X694400Y452900D03*
Y457400D03*
Y461900D03*
X689900Y457400D03*
Y452950D03*
X689700Y461850D03*
X710378Y100399D03*
Y88899D03*
X702391Y98510D03*
Y87010D03*
X698900Y457400D03*
X699000Y452950D03*
X698950Y461800D03*
G54D11*
X15364Y5500D03*
X10364D03*
X5500Y10384D03*
Y15384D03*
Y20384D03*
Y25384D03*
Y30384D03*
Y35384D03*
Y40384D03*
Y45384D03*
Y50384D03*
Y55384D03*
Y60384D03*
Y65384D03*
Y70384D03*
Y75384D03*
Y80384D03*
Y85384D03*
Y90384D03*
Y95384D03*
Y100384D03*
Y105384D03*
Y110384D03*
Y115384D03*
Y120384D03*
Y125384D03*
Y130384D03*
Y135384D03*
Y140384D03*
Y145384D03*
Y150384D03*
Y155384D03*
Y160384D03*
Y165384D03*
Y170384D03*
Y175384D03*
Y180384D03*
Y185384D03*
Y190384D03*
Y195384D03*
Y200384D03*
Y205384D03*
Y210384D03*
Y215384D03*
Y220384D03*
Y225384D03*
Y230384D03*
Y235384D03*
Y240384D03*
Y245384D03*
Y250384D03*
Y255384D03*
Y260384D03*
Y265384D03*
Y270384D03*
Y275384D03*
Y280384D03*
Y285384D03*
Y290384D03*
Y295384D03*
Y300384D03*
Y305384D03*
Y310384D03*
Y315384D03*
Y320384D03*
Y325384D03*
Y330384D03*
Y335384D03*
Y340384D03*
Y345384D03*
Y350384D03*
Y355384D03*
Y360384D03*
Y365384D03*
Y370384D03*
Y375384D03*
Y380384D03*
Y385384D03*
Y390384D03*
Y395384D03*
Y400384D03*
Y405384D03*
Y410384D03*
Y415384D03*
Y420384D03*
Y425384D03*
Y430384D03*
Y435384D03*
Y440384D03*
Y445384D03*
Y450384D03*
Y455384D03*
Y460384D03*
Y465384D03*
Y470384D03*
Y475384D03*
Y480384D03*
Y485384D03*
Y530384D03*
Y525384D03*
Y520384D03*
Y515384D03*
Y510384D03*
Y505384D03*
Y490384D03*
Y495384D03*
Y500384D03*
Y535384D03*
Y540384D03*
Y545384D03*
Y550384D03*
Y555384D03*
Y560384D03*
X10266Y565366D03*
X15266D03*
X75364Y5500D03*
X70364D03*
X65364D03*
X60364D03*
X55364D03*
X50364D03*
X45364D03*
X40364D03*
X35364D03*
X30364D03*
X25364D03*
X20364D03*
X54900Y204700D03*
X49900Y209700D03*
X59900D03*
X54900Y214700D03*
Y209700D03*
X33759Y274180D03*
X37830D03*
X23100Y292200D03*
Y287700D03*
X56026Y256117D03*
X69143Y334598D03*
X47443Y334198D03*
X27947Y334066D03*
X37049Y302949D03*
X23100Y318500D03*
Y314000D03*
X57350Y387800D03*
X46900Y378233D03*
X26100Y378352D03*
X69300Y378800D03*
X31240Y393440D03*
X49700Y391000D03*
X54040Y399390D03*
X20266Y565366D03*
X25266D03*
X30266D03*
X35266D03*
X40266D03*
X45266D03*
X50266D03*
X55266D03*
X60266D03*
X65266D03*
X70266D03*
X75266D03*
X95364Y5500D03*
X90364D03*
X85364D03*
X80364D03*
X81000Y291700D03*
X80896Y286695D03*
X90238Y334391D03*
X89895Y378426D03*
X102850Y452650D03*
X94488Y489888D03*
X80266Y565366D03*
X85266D03*
X90266D03*
X95266D03*
X100266D03*
X105266D03*
X110266D03*
X115266D03*
X120266D03*
X125266D03*
X130266D03*
X135266D03*
X158267Y25708D03*
Y47362D03*
Y53267D03*
Y41456D03*
Y31614D03*
Y19803D03*
X200364Y5500D03*
X195364D03*
X190364D03*
X185364D03*
X180364D03*
X175364D03*
X170364D03*
X191000Y110000D03*
X192830Y170500D03*
X197630D03*
X192830Y165700D03*
X197630D03*
X192830Y160900D03*
X197630D03*
X196963Y122029D03*
X184600Y137400D03*
X195400Y147200D03*
X195500Y142400D03*
X191900Y196100D03*
X196900D03*
X201700D03*
X196900Y200900D03*
X191900D03*
X196900Y205700D03*
X191900D03*
X196900Y210500D03*
X191900D03*
X201700Y205700D03*
Y200900D03*
X200266Y565366D03*
X195266D03*
X190266D03*
X185266D03*
X180266D03*
X175266D03*
X140266D03*
X145266D03*
X150266D03*
X155266D03*
X160266D03*
X165266D03*
X170266D03*
X260364Y5500D03*
X255364D03*
X250364D03*
X245364D03*
X240364D03*
X235364D03*
X230364D03*
X225364D03*
X220364D03*
X215364D03*
X210364D03*
X205364D03*
X242610Y53714D03*
X245250Y98250D03*
X261102Y77900D03*
X223994Y63225D03*
X242727Y63391D03*
X222700Y149300D03*
X227500D03*
X222700Y144500D03*
X227500D03*
X222700Y139700D03*
X227500D03*
X222700Y158900D03*
X227500D03*
X222700Y154100D03*
X227500D03*
X202430Y170500D03*
Y165700D03*
Y160900D03*
X222800Y204600D03*
X227600D03*
X222800Y219000D03*
X227600D03*
X222800Y214200D03*
X227600D03*
X222800Y209400D03*
X227600D03*
X222490Y235373D03*
X227290D03*
X222246Y229952D03*
X227046D03*
X222800Y223800D03*
X227600D03*
X222460Y240264D03*
X227260D03*
X245800Y279200D03*
X207600Y292400D03*
X253575Y320167D03*
X235500Y320100D03*
X218500Y320200D03*
X237600Y390500D03*
X261581Y370979D03*
X209052Y470198D03*
X213700Y448450D03*
X208900D03*
X203000Y451300D03*
X204252Y470198D03*
X204364Y478917D03*
X209164D03*
X205266Y565366D03*
X210266D03*
X215266D03*
X220266D03*
X225266D03*
X230266D03*
X235266D03*
X240266D03*
X245266D03*
X250266D03*
X255266D03*
X260266D03*
X312840Y42398D03*
X325378Y50351D03*
Y35351D03*
X310065Y32397D03*
X325364Y5500D03*
X320364D03*
X315364D03*
X310364D03*
X305364D03*
X300364D03*
X295364D03*
X290364D03*
X285364D03*
X280364D03*
X275364D03*
X270364D03*
X265364D03*
X270000Y29000D03*
Y33500D03*
Y38000D03*
Y42500D03*
X267188Y55192D03*
X285361Y78015D03*
X281761D03*
X289161Y58068D03*
X277514D03*
X287000Y117600D03*
Y125000D03*
X285500Y130400D03*
X290300D03*
X287300Y173000D03*
X292100D03*
X295650Y169554D03*
X295100Y130400D03*
X295801Y210294D03*
X292600Y214500D03*
X287800D03*
X317700Y275400D03*
X270143Y276969D03*
X323681Y259023D03*
X319881D03*
X295879Y255540D03*
X291079D03*
X286279D03*
X284498Y299976D03*
X299635Y292650D03*
X294250Y325000D03*
X277150Y332000D03*
X273165Y320351D03*
X266300Y412100D03*
X265266Y565366D03*
X270266D03*
X275266D03*
X280266D03*
X285266D03*
X290266D03*
X295266D03*
X300266D03*
X305266D03*
X310266D03*
X315266D03*
X320266D03*
X325266D03*
X388189Y48426D03*
X374016D03*
X359843D03*
X345670D03*
X388189Y34252D03*
X374016D03*
X359843D03*
X345670D03*
X388189Y20079D03*
X374016D03*
X359843D03*
X345670D03*
X388189Y5906D03*
X374016D03*
X359843D03*
X345670D03*
X381103Y38977D03*
X366929D03*
X352756D03*
X338583D03*
X381103Y24804D03*
X366929D03*
X352756D03*
X338583D03*
X381103Y53150D03*
X366929D03*
X352756D03*
X338583D03*
X330364Y5500D03*
X341757Y211056D03*
X337157Y206052D03*
X335701Y223995D03*
X352047Y220590D03*
X368714Y261134D03*
X339500Y260400D03*
X327868Y290125D03*
X365996Y287265D03*
Y272841D03*
X366169Y246591D03*
X370669D03*
X338650Y281350D03*
X361996Y272841D03*
X368050Y337200D03*
X370250Y347600D03*
X379148Y337184D03*
X384341Y315377D03*
X377324Y302844D03*
X360050Y337200D03*
X348600Y323900D03*
X359400Y347200D03*
X327365Y433732D03*
X337900Y431200D03*
X350586Y495815D03*
X355523Y495025D03*
X360461Y494236D03*
X365398Y493446D03*
X370335Y492656D03*
X375272Y491866D03*
X380210Y491077D03*
X385169Y490563D03*
X329156Y545492D03*
Y540492D03*
Y535492D03*
Y530492D03*
Y525492D03*
Y520492D03*
Y515492D03*
Y560492D03*
Y555492D03*
Y550492D03*
X444882Y48426D03*
X430709D03*
X416536D03*
X402363D03*
X444882Y34252D03*
X430709D03*
X416536D03*
X402363D03*
X444882Y20079D03*
X430709D03*
X416536D03*
X402363D03*
X444882Y5906D03*
X430709D03*
X416536D03*
X402363D03*
X437796Y38977D03*
X423622D03*
X409449D03*
X395276D03*
X437796Y24804D03*
X423622D03*
X409449D03*
X395276D03*
X437796Y53150D03*
X423622D03*
X409449D03*
X395276D03*
X448818Y232284D03*
X440944D03*
X433070D03*
X433071Y224410D03*
X440945D03*
X448819D03*
X397638Y232284D03*
X389764Y204725D03*
Y220473D03*
Y208662D03*
Y228347D03*
X409449Y236221D03*
X393701Y228347D03*
Y216536D03*
Y212599D03*
X397638D03*
X401575D03*
X393701Y220473D03*
X397638Y200788D03*
X405512D03*
X413386D03*
X421260D03*
X429134D03*
X437008D03*
X444882D03*
X409449Y212599D03*
Y224410D03*
X417323Y212599D03*
X425197D03*
X433071D03*
X440945D03*
X448819D03*
X425197Y224410D03*
X417323D03*
X413386D03*
X433071Y275591D03*
X397638Y240158D03*
Y295276D03*
X405512D03*
X397638Y271654D03*
X409449Y267717D03*
X397638Y287402D03*
X405512D03*
X397638Y279528D03*
X409449Y275591D03*
X397638Y259843D03*
X405512D03*
Y255906D03*
X389764Y251969D03*
X393701D03*
X397638D03*
X409449Y244095D03*
Y255906D03*
X417323Y299213D03*
X421260Y291339D03*
X425197Y259843D03*
X417323Y267717D03*
X429134Y271654D03*
X417323Y275591D03*
X429134Y248032D03*
X425197Y255906D03*
X417323D03*
X413386Y259843D03*
X429134Y279528D03*
X421260D03*
X433071Y240158D03*
Y248032D03*
X448819Y240158D03*
X440945D03*
X448819Y248032D03*
X440945D03*
X444959Y352053D03*
X389559Y337103D03*
X421500Y337500D03*
X427500D03*
X448431Y348737D03*
X397638Y326772D03*
X409449D03*
X397638Y318898D03*
X409449D03*
Y314961D03*
X397638Y311024D03*
X409449D03*
X417323Y326772D03*
Y318898D03*
X425197Y311024D03*
X433071D03*
X397638Y303150D03*
X405512D03*
X413386Y307087D03*
X440945Y318898D03*
X448819D03*
X417323Y307087D03*
Y303150D03*
X410236Y419291D03*
Y404331D03*
Y449212D03*
Y434252D03*
X405169Y490563D03*
X410169D03*
X415169D03*
X420169D03*
X425169D03*
X430169D03*
X435169D03*
X440169D03*
X445146Y490850D03*
X450083Y491640D03*
X390169Y490563D03*
X395169D03*
X400169D03*
X501575Y48426D03*
X487402D03*
X473229D03*
X459055D03*
X501575Y34252D03*
X487402D03*
X473229D03*
X459055D03*
X501575Y20079D03*
X487402D03*
X473229D03*
X459055D03*
X501575Y5906D03*
X487402D03*
X473229D03*
X459055D03*
X508662Y38977D03*
X494489D03*
X480315D03*
X466142D03*
X451969D03*
X508662Y24804D03*
X494489D03*
X480315D03*
X466142D03*
X451969D03*
X508662Y53150D03*
X494489D03*
X480315D03*
X466142D03*
X451969D03*
X456693Y232284D03*
X464567D03*
X472441D03*
X480315D03*
X456693Y200788D03*
X464567D03*
X492126Y208662D03*
Y204725D03*
X500000D03*
X472441Y200788D03*
X480315D03*
X488189D03*
X492126D03*
X460630Y212599D03*
X468504D03*
X492126Y216536D03*
X476378Y212599D03*
X484252D03*
X492126D03*
X503937D03*
X507874Y208662D03*
X503937Y204725D03*
X507874D03*
X503937Y236221D03*
Y228347D03*
X492126Y220473D03*
X503937D03*
X511811Y208662D03*
X507874Y200788D03*
X511811D03*
X472441Y224410D03*
X464567D03*
X456693D03*
X480315D03*
X492126D03*
X488189D03*
X492126Y232284D03*
Y236221D03*
X456693Y279528D03*
X472441Y295276D03*
X503937Y251969D03*
Y244095D03*
Y271654D03*
Y259843D03*
Y287402D03*
Y279528D03*
Y295276D03*
X488189Y287402D03*
X492126Y291339D03*
X488189D03*
X472441Y240158D03*
X456693Y259843D03*
X464567Y240158D03*
X456693D03*
X480315Y267717D03*
Y271654D03*
Y275591D03*
Y279528D03*
Y283465D03*
X492126Y267717D03*
X488189Y271654D03*
X492126Y275591D03*
X488189Y279528D03*
X492126Y283465D03*
X480315Y259843D03*
Y240158D03*
Y244095D03*
Y248032D03*
Y251969D03*
Y255906D03*
X488189Y259843D03*
X492126Y240158D03*
X488189D03*
X492126Y248032D03*
X488189D03*
Y255906D03*
X472441Y275591D03*
Y267717D03*
Y283465D03*
Y259843D03*
Y251969D03*
X456693Y248032D03*
X464567D03*
X481359Y347727D03*
X472441Y303150D03*
X460630Y318898D03*
X468504D03*
X456693Y303150D03*
X476378Y318898D03*
X484252D03*
X492126D03*
X500000D03*
X496063Y307087D03*
X480315Y303150D03*
X492126D03*
X507874Y318898D03*
Y307087D03*
X511811D03*
X503937Y303150D03*
X485100Y366800D03*
X490000Y363700D03*
X502850Y368500D03*
X469832Y494799D03*
X474769Y495589D03*
X455020Y492430D03*
X459958Y493219D03*
X464895Y494009D03*
X497636Y515532D03*
Y520532D03*
Y525532D03*
Y530532D03*
Y535532D03*
Y540532D03*
Y545532D03*
Y550532D03*
Y555532D03*
Y560532D03*
X502550Y565366D03*
X507550D03*
X512550D03*
X572441Y48426D03*
X558268D03*
X544095D03*
X529922D03*
X515748D03*
X572441Y34252D03*
X558268D03*
X544095D03*
X529922D03*
X515748D03*
X572441Y20079D03*
X558268D03*
X544095D03*
X529922D03*
X515748D03*
X572441Y5906D03*
X558268D03*
X544095D03*
X529922D03*
X515748D03*
X565355Y38977D03*
X551181D03*
X537008D03*
X522835D03*
X565355Y24804D03*
X551181D03*
X537008D03*
X522835D03*
X565355Y53150D03*
X551181D03*
X537008D03*
X522835D03*
X557500Y231900D03*
X545000D03*
X517000Y226370D03*
Y218500D03*
Y234252D03*
X554717Y255796D03*
X542217D03*
X554975Y248209D03*
X542475D03*
X555865Y240638D03*
X543365D03*
X517500Y297218D03*
X518647Y288943D03*
X515748Y240158D03*
Y267717D03*
Y255906D03*
Y248032D03*
Y283465D03*
Y275591D03*
Y318898D03*
Y307087D03*
X554250Y457500D03*
X517125Y488975D03*
X517550Y565366D03*
X522550D03*
X527550D03*
X532550D03*
X537550D03*
X542550D03*
X547550D03*
X552550D03*
X557550D03*
X562550D03*
X567550D03*
X572550D03*
X586614Y48426D03*
Y34252D03*
Y20079D03*
Y5906D03*
X579528Y38977D03*
Y24804D03*
Y53150D03*
X591446Y6545D03*
X596446D03*
X601446D03*
X606446D03*
X611446D03*
X616446D03*
X621446D03*
X636446D03*
X631446D03*
X626446D03*
X635942Y97351D03*
X618400Y173443D03*
X617600Y134400D03*
X634000Y234200D03*
X630000D03*
X598600Y247800D03*
Y253100D03*
X633800Y239600D03*
X629900Y239700D03*
X633800Y245700D03*
X629900Y245800D03*
X634100Y252000D03*
X629900D03*
X590050Y337950D03*
X590200Y334350D03*
X627020Y393364D03*
X629770Y369320D03*
X629400Y414324D03*
X630000Y464900D03*
X626300D03*
X577330Y464430D03*
X599900Y438300D03*
X587890Y426720D03*
X577550Y565366D03*
X582550D03*
X587550D03*
X592550D03*
X597550D03*
X602550D03*
X607550D03*
X612550D03*
X617550D03*
X622550D03*
X627550D03*
X632550D03*
X641446Y6545D03*
X646446D03*
X651446D03*
X652551Y40716D03*
X696446Y6545D03*
X691446D03*
X661446D03*
X656446D03*
X686446D03*
X681446D03*
X676446D03*
X671446D03*
X666446D03*
X655914Y39932D03*
X667149Y23411D03*
X637003Y68809D03*
X648207Y70750D03*
X654330Y113385D03*
X688976D03*
X646643Y97859D03*
X644100Y111811D03*
X654330Y154330D03*
X663778Y166928D03*
X673227Y157479D03*
X679526Y144880D03*
X695274Y135431D03*
X698425Y129134D03*
X663778Y160629D03*
Y154330D03*
Y135431D03*
X692124D03*
X673227Y144880D03*
X685825Y138581D03*
X679526D03*
X673227D03*
X666928D03*
X648032Y129134D03*
X657480Y122834D03*
X698425Y135433D03*
Y138582D03*
X692125D03*
X682677Y148031D03*
X688976D03*
X695275D03*
X682677Y154330D03*
X688976D03*
X695275D03*
Y160629D03*
X688976D03*
X682677Y160630D03*
X679527Y163779D03*
X695275Y166929D03*
X688976D03*
X682677D03*
X695275Y173228D03*
X688976D03*
X682677D03*
X654330Y170078D03*
X648031Y163779D03*
X654330D03*
X651181Y157480D03*
X670078Y154330D03*
X644882Y157480D03*
X666929Y125984D03*
X657480Y129134D03*
X651181Y151181D03*
X698425Y116535D03*
X648059Y151191D03*
X685827Y125985D03*
X676377Y116536D03*
X663778Y176377D03*
Y173227D03*
Y170078D03*
X670078Y166928D03*
Y173227D03*
X654330Y176377D03*
X639108Y167800D03*
X648057Y141721D03*
X648032Y135434D03*
Y122835D03*
X660629Y116536D03*
X666929Y116535D03*
X698426Y122835D03*
X692148Y129119D03*
X670116Y132283D03*
X673229Y125985D03*
X679528D03*
X666928Y144880D03*
X651181Y188976D03*
X679527Y182679D03*
Y188975D03*
X692126Y182676D03*
Y185827D03*
Y179527D03*
X697069Y207157D03*
X663400Y234100D03*
X663200Y238100D03*
X682676Y179526D03*
Y188975D03*
X682677Y182677D03*
X682676Y185826D03*
X676377Y201574D03*
Y204723D03*
X685826Y198424D03*
X663778Y182676D03*
Y179526D03*
X654330Y182676D03*
X660629Y192125D03*
X666929D03*
X660630Y198425D03*
X676377Y198424D03*
X685826Y201574D03*
X682677Y192125D03*
X688976D03*
X698425D03*
X640931Y181102D03*
X646594Y210875D03*
X640584Y194127D03*
X695600Y240354D03*
X682700D03*
X695625Y282250D03*
X669125Y280405D03*
X663000Y249200D03*
X663100Y252700D03*
X674841Y262854D03*
X659977Y323082D03*
X664731Y324099D03*
X660115Y351977D03*
Y356777D03*
X664731Y343299D03*
X655500Y360000D03*
X660115Y361577D03*
X664731Y338499D03*
Y333699D03*
Y328899D03*
X659977Y342282D03*
Y332682D03*
Y347082D03*
Y337482D03*
Y327882D03*
X662306Y365477D03*
X657673Y365400D03*
X672281Y378883D03*
X693500Y373300D03*
X694765Y406915D03*
X685750Y419460D03*
X642900Y395400D03*
X694950Y477850D03*
Y473050D03*
X667414Y431956D03*
X637550Y565366D03*
X642550D03*
X647550D03*
X652550D03*
X657550D03*
X662550D03*
X667550D03*
X672550D03*
X677550D03*
X682550D03*
X687550D03*
X692550D03*
X697550D03*
X758267Y48426D03*
X744094D03*
X729921D03*
X715748D03*
X758267Y34252D03*
X744094D03*
X729921D03*
X715748D03*
X758267Y20079D03*
X744094D03*
X729921D03*
X715748D03*
X758267Y5906D03*
X744094D03*
X729921D03*
X715748D03*
X751181Y53150D03*
X737007D03*
X722834D03*
X708661D03*
X751181Y38977D03*
X737007D03*
X722834D03*
X708661D03*
X751181Y24804D03*
X737007D03*
X722834D03*
X708661D03*
X701446Y6545D03*
X728788Y88540D03*
X725295Y88609D03*
X752853Y100900D03*
X733069Y166930D03*
X704725Y135434D03*
X707874Y141732D03*
X701574Y138582D03*
X701575Y135433D03*
X711023Y132283D03*
X704724D03*
X717322Y129133D03*
X726770Y166930D03*
Y173229D03*
X701574Y148031D03*
X707873D03*
X701574Y154330D03*
X707873D03*
Y160629D03*
X701574D03*
X707873Y166929D03*
X701574D03*
X707873Y173228D03*
X701574D03*
X711023Y122834D03*
X717322D03*
X723622D03*
X711023Y141732D03*
X743452Y151815D03*
X714172Y173227D03*
Y144880D03*
Y151180D03*
X717322Y144880D03*
Y151180D03*
X714172Y163778D03*
Y157479D03*
X717322Y163778D03*
Y157479D03*
Y166928D03*
X720472Y173228D03*
Y148031D03*
Y141732D03*
Y160629D03*
Y154330D03*
X720471Y166928D03*
X717322Y141731D03*
X758050Y164050D03*
X704725Y122835D03*
X720472Y135433D03*
X717322Y182676D03*
X711024Y188976D03*
X701575Y182676D03*
X711022Y185825D03*
X701575Y185827D03*
Y179527D03*
X726770Y179528D03*
Y185827D03*
X743200Y227900D03*
X726770Y192126D03*
X730694Y224473D03*
X726656Y235244D03*
X711022Y179526D03*
X714172D03*
X722523Y221315D03*
X720437Y185829D03*
X720472Y179527D03*
Y192125D03*
X711022Y182676D03*
X704724Y192125D03*
X711024D03*
X742200Y340800D03*
Y345600D03*
X737400Y340800D03*
Y345600D03*
X732600Y331200D03*
Y336000D03*
Y340800D03*
Y355200D03*
Y350400D03*
Y345600D03*
X701100Y315900D03*
X705900D03*
X701100Y311100D03*
X705900D03*
Y306300D03*
X701100D03*
X705320Y420610D03*
X735570Y424760D03*
X718110Y442960D03*
X708355Y454712D03*
X719920Y429700D03*
X702550Y565366D03*
X707550D03*
X712550D03*
X717550D03*
X722550D03*
X727550D03*
X732550D03*
X737550D03*
X742550D03*
X747550D03*
X752550D03*
X757550D03*
X821272Y49340D03*
Y44340D03*
Y39340D03*
Y34340D03*
Y29340D03*
Y24340D03*
Y19340D03*
Y14340D03*
Y9340D03*
X815364Y5500D03*
X810364D03*
X805364D03*
X800364D03*
X795364D03*
X790364D03*
X785364D03*
X780364D03*
X775364D03*
X770364D03*
X765364D03*
X799250Y71125D03*
X821272Y114340D03*
Y109340D03*
Y104340D03*
Y99340D03*
Y94340D03*
Y89340D03*
Y84340D03*
Y79340D03*
Y74340D03*
Y69340D03*
Y64340D03*
Y59340D03*
Y54340D03*
X772107Y83046D03*
X799493Y93250D03*
X821272Y174340D03*
Y169340D03*
Y164340D03*
Y159340D03*
Y154340D03*
Y149340D03*
Y144340D03*
Y139340D03*
Y134340D03*
Y129340D03*
Y124340D03*
Y119340D03*
X782500Y134283D03*
X773000Y119600D03*
X776600D03*
X794500Y134283D03*
X785000Y158900D03*
X760600Y173700D03*
X821272Y234340D03*
Y229340D03*
Y224340D03*
Y219340D03*
Y214340D03*
Y209340D03*
Y204340D03*
Y199340D03*
Y194340D03*
Y189340D03*
Y184340D03*
Y179340D03*
X790000Y224700D03*
X795498Y246171D03*
X821272Y299340D03*
Y294340D03*
Y289340D03*
Y284340D03*
Y279340D03*
Y274340D03*
Y269340D03*
Y264340D03*
Y259340D03*
Y254340D03*
Y249340D03*
Y244340D03*
Y239340D03*
X793912Y297020D03*
X793837Y283696D03*
X821272Y359340D03*
Y354340D03*
Y349340D03*
Y344340D03*
Y339340D03*
Y334340D03*
Y329340D03*
Y324340D03*
Y319340D03*
Y314340D03*
Y309340D03*
Y304340D03*
X786610Y321340D03*
X761520Y339110D03*
X821272Y424340D03*
Y419340D03*
Y414340D03*
Y409340D03*
Y404340D03*
Y399340D03*
Y394340D03*
Y389340D03*
Y384340D03*
Y379340D03*
Y374340D03*
Y369340D03*
Y364340D03*
Y484340D03*
Y479340D03*
Y474340D03*
Y469340D03*
Y464340D03*
Y459340D03*
Y454340D03*
Y449340D03*
Y444340D03*
Y439340D03*
Y434340D03*
Y429340D03*
Y504340D03*
Y509340D03*
Y514340D03*
Y519340D03*
Y524340D03*
Y529340D03*
Y549340D03*
Y544340D03*
Y539340D03*
Y534340D03*
Y499340D03*
Y494340D03*
Y489340D03*
X762550Y565366D03*
X767550D03*
X772550D03*
X777550D03*
X782550D03*
X787550D03*
X792550D03*
X797550D03*
X802550D03*
X807550D03*
X812550D03*
X817550D03*
X821272Y559340D03*
Y554340D03*
G54D25*
X145900Y136500D03*
X632750Y295641D03*
Y334300D03*
X688978Y135435D03*
X682679D03*
X676379D03*
X804412Y185332D03*
X800612Y185432D03*
G54D27*
X234450Y73000D03*
X381103Y10651D03*
X366929D03*
X352756D03*
X338583D03*
X437796D03*
X423622D03*
X409449D03*
X395276D03*
X433070Y279528D03*
X508661Y10651D03*
X494488D03*
X480315D03*
X466142D03*
X451969D03*
X565354D03*
X551181D03*
X537008D03*
X522835D03*
X579527D03*
X627455Y185364D03*
X618300Y288745D03*
Y327654D03*
X673229Y166929D03*
Y173228D03*
X660629Y138584D03*
Y141732D03*
X751181Y10651D03*
X737007D03*
X722834D03*
X708661D03*
G54D19*
X116063Y14567D03*
G54D10*
X15812Y-86244D03*
X27058Y25484D03*
X81539Y542850D03*
X411652Y539991D03*
X812711Y-86834D03*
X798456Y26432D03*
G54D33*
X389764Y460630D03*
X437008D03*
G54D20*
X116063Y39075D03*
G54D31*
X374015Y156220D03*
X531496Y371299D03*
X596456Y116142D03*
X781496Y198818D03*
G54D29*
X295275Y531496D03*
X531495D03*
G54D18*
X37402Y535158D03*
X789370D03*
G54D12*
X75119Y111166D03*
X105619D03*
X81119D03*
X87619D03*
X93619D03*
X99619D03*
X82600Y232000D03*
X87300Y230650D03*
X83232Y399956D03*
X229000Y95000D03*
X464567Y299214D03*
X751878Y276817D03*
X704115Y414466D03*
Y409666D03*
Y404866D03*
Y400066D03*
X760715Y210200D03*
Y201700D03*
Y214200D03*
X781640Y278660D03*
G54D15*
X39416Y206616D03*
X65500Y237800D03*
X70500D03*
X75500D03*
X23800Y211200D03*
X27500D03*
X59700Y178600D03*
X68400Y177950D03*
X76800Y178200D03*
X92300Y199400D03*
Y209400D03*
Y204400D03*
X90800Y217900D03*
X78850Y221000D03*
X92300Y190900D03*
X81300Y178050D03*
X85700Y178000D03*
X222818Y364806D03*
X222909Y371864D03*
X223000Y378246D03*
X296385Y108227D03*
X325651Y439668D03*
X421258Y232283D03*
X448818Y299214D03*
X425196Y283466D03*
X433070Y255905D03*
X401575Y410039D03*
X410433D03*
X419292D03*
X401575Y425000D03*
X410433D03*
X419292D03*
X401575Y439961D03*
X410433D03*
X419292D03*
X401575Y454921D03*
X410433D03*
X419292D03*
X467774Y362151D03*
X467100Y357500D03*
X464500Y347410D03*
X505500Y464400D03*
Y469200D03*
Y474000D03*
X509500Y450800D03*
Y446000D03*
Y441200D03*
X542627Y324049D03*
X555127D03*
X541278Y315738D03*
X553778D03*
X541221Y308771D03*
X553721D03*
X541193Y301280D03*
X553693D03*
X629813Y27661D03*
X634169Y166500D03*
X594025Y284017D03*
X610750Y336850D03*
X594050Y301755D03*
X598152Y370130D03*
X594200Y390400D03*
X609400Y446850D03*
X604400Y456100D03*
Y451850D03*
Y447350D03*
Y460350D03*
X609400Y450450D03*
Y454050D03*
Y457650D03*
Y461250D03*
X599503Y447123D03*
Y450723D03*
Y454323D03*
Y457923D03*
X604400Y464850D03*
X609400D03*
X599503Y461523D03*
Y465123D03*
X656450Y28000D03*
X657480Y151219D03*
X676379Y182678D03*
Y192126D03*
X670080Y182678D03*
X672800Y438832D03*
X696950Y441400D03*
X751133Y313984D03*
X754227Y301111D03*
X725247Y458974D03*
X724422Y464139D03*
X724400Y485200D03*
Y480400D03*
Y475600D03*
X701120Y430620D03*
X724400Y490200D03*
G54D34*
X448818Y259843D03*
Y267718D03*
X440944D03*
Y259843D03*
X456693Y267718D03*
X464567D03*
Y279529D03*
Y259843D03*
G54D26*
X157650Y418100D03*
X160400Y422900D03*
X160550Y414100D03*
X160400Y427700D03*
Y432500D03*
X786300Y309900D03*
G54D28*
X248169Y74454D03*
X437057Y279414D03*
X632750Y292195D03*
Y330854D03*
X632900Y344950D03*
X612300Y356850D03*
X608500Y315000D03*
X634000Y306300D03*
G54D35*
X433071Y263781D03*
G54D36*
X590537Y170119D03*
X586912Y154495D03*
X584314Y166721D03*
X596233Y145667D03*
X593635Y157893D03*
X588901Y134308D03*
X586303Y146534D03*
X577699Y123469D03*
X575101Y135695D03*
X589966Y210195D03*
X587368Y222421D03*
X585841Y194571D03*
X583243Y206797D03*
X581716Y178947D03*
X579118Y191173D03*
X587939Y182345D03*
G54D17*
X37402Y499724D03*
X789370D03*
%LPC*%
G75*
G54D37*
G01X-34018Y-300855D02*
G02I-12000J0D01*
G01X-39168D02*
G02I-6850J0D01*
G01X-30018D02*
X-62018D01*
G01X-30018Y-316855D02*
Y-396855D01*
G01D02*
X1320682D01*
G01X-30018Y-352355D02*
X1320682D01*
G01X-46018Y-316855D02*
Y-284855D01*
G01X-30018Y-316855D02*
X1320682D01*
G01X533182D02*
Y-396855D01*
G01X670682Y-316855D02*
Y-396855D01*
G01X785682Y-316855D02*
Y-396855D01*
G01X953182Y-316855D02*
Y-396855D01*
G01X1123182Y-316855D02*
Y-396855D01*
G01X1320682Y-316855D02*
Y-396855D01*
G01X1348682Y-300855D02*
G02I-12000J0D01*
G01X1343532D02*
G02I-6850J0D01*
G01X1336682Y-316855D02*
Y-284855D01*
G01X1352682Y-300855D02*
X1320682D01*
G54D38*
G01X121778Y-377522D02*
X122652Y-376647D01*
X123307Y-375189D01*
X123744Y-373146D01*
X123307Y-371397D01*
X122434Y-370230D01*
X120905Y-369355D01*
X115010D01*
Y-386855D01*
X122215D01*
X123744Y-385689D01*
X124617Y-383938D01*
X125054Y-381897D01*
X124617Y-379855D01*
X123307Y-378105D01*
X121778Y-377522D01*
X115010D01*
G01X134475Y-386855D02*
Y-375189D01*
G01Y-377522D02*
X135567Y-376355D01*
X136659Y-375480D01*
X138187Y-375189D01*
X139278Y-375480D01*
X140589Y-376355D01*
G01X150447Y-392105D02*
X151757Y-392688D01*
X153504Y-392105D01*
X154595Y-390939D01*
X155469Y-389480D01*
X156778Y-384814D01*
X159617Y-375189D01*
G01X152630D02*
X156778Y-384814D01*
G01X176025Y-376647D02*
X174497Y-375480D01*
X173187Y-375189D01*
X171440Y-375772D01*
X170130Y-376938D01*
X169257Y-378980D01*
X169038Y-381022D01*
X169257Y-383064D01*
X170130Y-384814D01*
X171440Y-386272D01*
X173187Y-386855D01*
X174715Y-386272D01*
X176025Y-385105D01*
G01X186757Y-378980D02*
X193744D01*
X193089Y-376938D01*
X191997Y-375772D01*
X190469Y-375189D01*
X188940Y-375480D01*
X187630Y-376355D01*
X186757Y-378397D01*
X186320Y-380147D01*
Y-381897D01*
X186757Y-383647D01*
X187849Y-385397D01*
X189159Y-386563D01*
X190687Y-386855D01*
X192215Y-386272D01*
X193744Y-384522D01*
G01X229835Y-370814D02*
X228525Y-369938D01*
X226997Y-369355D01*
X225250D01*
X223285Y-370230D01*
X221757Y-371688D01*
X220665Y-373439D01*
X219792Y-376355D01*
X219573Y-378980D01*
X220010Y-381605D01*
X220665Y-383355D01*
X221975Y-385105D01*
X223504Y-386272D01*
X225032Y-386855D01*
X226560D01*
X228089Y-386272D01*
X229399Y-385397D01*
X230491Y-384231D01*
G01X246462Y-386855D02*
Y-375189D01*
G01Y-377230D02*
X245589Y-376064D01*
X244278Y-375480D01*
X242750Y-375189D01*
X241222Y-375772D01*
X239912Y-376938D01*
X239038Y-378688D01*
X238602Y-381022D01*
X239038Y-383355D01*
X239912Y-385105D01*
X241222Y-386272D01*
X242750Y-386855D01*
X244278Y-386563D01*
X245589Y-385689D01*
X246462Y-384522D01*
G01X256320Y-386855D02*
Y-375189D01*
G01Y-378105D02*
X257194Y-376647D01*
X258504Y-375480D01*
X260250Y-375189D01*
X261778Y-375480D01*
X263089Y-376647D01*
X263744Y-378688D01*
Y-386855D01*
G01X272947Y-392105D02*
X274257Y-392688D01*
X276004Y-392105D01*
X277095Y-390939D01*
X277969Y-389480D01*
X279278Y-384814D01*
X282117Y-375189D01*
G01X275130D02*
X279278Y-384814D01*
G01X295032Y-386855D02*
X293722Y-386563D01*
X292412Y-385397D01*
X291538Y-383355D01*
X291102Y-381022D01*
X291538Y-378688D01*
X292412Y-376647D01*
X293722Y-375480D01*
X295032Y-375189D01*
X296342Y-375480D01*
X297652Y-376647D01*
X298525Y-378688D01*
X298744Y-381022D01*
X298525Y-383355D01*
X297652Y-385397D01*
X296342Y-386563D01*
X295032Y-386855D01*
G01X308820D02*
Y-375189D01*
G01Y-378105D02*
X309694Y-376647D01*
X311004Y-375480D01*
X312750Y-375189D01*
X314278Y-375480D01*
X315589Y-376647D01*
X316244Y-378688D01*
Y-386855D01*
G01X342947Y-384522D02*
X344694Y-385980D01*
X346659Y-386855D01*
X348405D01*
X350152Y-385980D01*
X351462Y-384522D01*
X352117Y-382480D01*
X351680Y-380439D01*
X350589Y-378688D01*
X348624Y-377522D01*
X346004Y-376938D01*
X344475Y-375772D01*
X343820Y-373730D01*
X344257Y-371688D01*
X345349Y-370230D01*
X346877Y-369355D01*
X348405D01*
X349934Y-369938D01*
X351244Y-371397D01*
G01X369835Y-370814D02*
X368525Y-369938D01*
X366997Y-369355D01*
X365250D01*
X363285Y-370230D01*
X361757Y-371688D01*
X360665Y-373439D01*
X359792Y-376355D01*
X359573Y-378980D01*
X360010Y-381605D01*
X360665Y-383355D01*
X361975Y-385105D01*
X363504Y-386272D01*
X365032Y-386855D01*
X366560D01*
X368089Y-386272D01*
X369399Y-385397D01*
X370491Y-384231D01*
G01X387335Y-370814D02*
X386025Y-369938D01*
X384497Y-369355D01*
X382750D01*
X380785Y-370230D01*
X379257Y-371688D01*
X378165Y-373439D01*
X377292Y-376355D01*
X377073Y-378980D01*
X377510Y-381605D01*
X378165Y-383355D01*
X379475Y-385105D01*
X381004Y-386272D01*
X382532Y-386855D01*
X384060D01*
X385589Y-386272D01*
X386899Y-385397D01*
X387991Y-384231D01*
G01X210605Y-341855D02*
Y-324355D01*
X216282Y-338938D01*
X221959Y-324355D01*
Y-341855D01*
G01X233782D02*
X232472Y-341563D01*
X231162Y-340397D01*
X230288Y-338355D01*
X229852Y-336022D01*
X230288Y-333688D01*
X231162Y-331647D01*
X232472Y-330480D01*
X233782Y-330189D01*
X235092Y-330480D01*
X236402Y-331647D01*
X237275Y-333688D01*
X237494Y-336022D01*
X237275Y-338355D01*
X236402Y-340397D01*
X235092Y-341563D01*
X233782Y-341855D01*
G01X255212Y-324355D02*
Y-341855D01*
G01Y-339231D02*
X254339Y-340689D01*
X253028Y-341563D01*
X251500Y-341855D01*
X249754Y-341272D01*
X248444Y-339814D01*
X247570Y-338064D01*
X247352Y-336022D01*
X247570Y-333980D01*
X248444Y-332230D01*
X249754Y-330772D01*
X251500Y-330189D01*
X253028Y-330480D01*
X254120Y-331064D01*
X255212Y-332230D01*
G01X265507Y-333980D02*
X272494D01*
X271839Y-331938D01*
X270747Y-330772D01*
X269219Y-330189D01*
X267690Y-330480D01*
X266380Y-331355D01*
X265507Y-333397D01*
X265070Y-335147D01*
Y-336897D01*
X265507Y-338647D01*
X266599Y-340397D01*
X267909Y-341563D01*
X269437Y-341855D01*
X270965Y-341272D01*
X272494Y-339522D01*
G01X286282Y-341855D02*
Y-324355D01*
G01X566882Y-386855D02*
Y-369355D01*
X564262Y-372855D01*
G01Y-386855D02*
X569502D01*
G01X580234Y-379564D02*
X581762Y-377522D01*
X583072Y-376355D01*
X584819Y-375772D01*
X586347Y-376355D01*
X587439Y-377522D01*
X588312Y-379272D01*
X588530Y-381313D01*
X588312Y-383064D01*
X587439Y-384814D01*
X586128Y-386272D01*
X584600Y-386855D01*
X582854Y-386272D01*
X581325Y-384522D01*
X580452Y-381897D01*
X580234Y-378980D01*
X580670Y-375189D01*
X581325Y-373146D01*
X582417Y-371105D01*
X583945Y-369647D01*
X585474Y-369355D01*
X587002Y-369938D01*
X588094Y-371397D01*
G01X597079Y-383355D02*
X598388Y-385397D01*
X600135Y-386563D01*
X602100Y-386855D01*
X603847Y-386563D01*
X605594Y-385105D01*
X606685Y-383355D01*
X606904Y-381605D01*
X606467Y-379564D01*
X604939Y-378105D01*
X603410Y-377522D01*
X601445D01*
G01X603410D02*
X604720Y-376647D01*
X605812Y-375189D01*
X606249Y-373439D01*
X605812Y-371688D01*
X604720Y-370230D01*
X602755Y-369355D01*
X600790Y-369647D01*
X598825Y-370814D01*
G01X619382Y-386855D02*
Y-369355D01*
X616762Y-372855D01*
G01Y-386855D02*
X622002D01*
G01X632734Y-379564D02*
X634262Y-377522D01*
X635572Y-376355D01*
X637319Y-375772D01*
X638847Y-376355D01*
X639939Y-377522D01*
X640812Y-379272D01*
X641030Y-381313D01*
X640812Y-383064D01*
X639939Y-384814D01*
X638628Y-386272D01*
X637100Y-386855D01*
X635354Y-386272D01*
X633825Y-384522D01*
X632952Y-381897D01*
X632734Y-378980D01*
X633170Y-375189D01*
X633825Y-373146D01*
X634917Y-371105D01*
X636445Y-369647D01*
X637974Y-369355D01*
X639502Y-369938D01*
X640594Y-371397D01*
G01X553765Y-341855D02*
Y-324355D01*
X559005D01*
X560752Y-325230D01*
X562062Y-327272D01*
X562499Y-329605D01*
X562062Y-331938D01*
X560970Y-333688D01*
X559005Y-334564D01*
X553765D01*
G01X580435Y-325814D02*
X579125Y-324938D01*
X577597Y-324355D01*
X575850D01*
X573885Y-325230D01*
X572357Y-326688D01*
X571265Y-328439D01*
X570392Y-331355D01*
X570173Y-333980D01*
X570610Y-336605D01*
X571265Y-338355D01*
X572575Y-340105D01*
X574104Y-341272D01*
X575632Y-341855D01*
X577160D01*
X578689Y-341272D01*
X579999Y-340397D01*
X581091Y-339231D01*
G01X594878Y-332522D02*
X595752Y-331647D01*
X596407Y-330189D01*
X596844Y-328146D01*
X596407Y-326397D01*
X595534Y-325230D01*
X594005Y-324355D01*
X588110D01*
Y-341855D01*
X595315D01*
X596844Y-340689D01*
X597717Y-338938D01*
X598154Y-336897D01*
X597717Y-334855D01*
X596407Y-333105D01*
X594878Y-332522D01*
X588110D01*
G01X604082Y-347688D02*
X617182D01*
G01X623110Y-341855D02*
Y-324355D01*
X633154Y-341855D01*
Y-324355D01*
G01X645632Y-341855D02*
X643885Y-341563D01*
X642357Y-340397D01*
X641047Y-338647D01*
X640173Y-336605D01*
X639737Y-334272D01*
Y-331938D01*
X640173Y-329605D01*
X641047Y-327563D01*
X642357Y-325814D01*
X643885Y-324647D01*
X645632Y-324355D01*
X647378Y-324647D01*
X648907Y-325814D01*
X650217Y-327563D01*
X651091Y-329605D01*
X651527Y-331938D01*
Y-334272D01*
X651091Y-336605D01*
X650217Y-338647D01*
X648907Y-340397D01*
X647378Y-341563D01*
X645632Y-341855D01*
G01X696473Y-324355D02*
X701932Y-341855D01*
X707391Y-324355D01*
G01X723799Y-341855D02*
X715065D01*
Y-324355D01*
X723799D01*
G01X720305Y-332813D02*
X715065D01*
G01X732565Y-341855D02*
Y-324355D01*
X738024D01*
X739770Y-325230D01*
X740862Y-326397D01*
X741299Y-328730D01*
X740862Y-331064D01*
X739552Y-332522D01*
X738024Y-333397D01*
X732565D01*
G01X738024D02*
X741299Y-341855D01*
G01X754432Y-342438D02*
X753995Y-342147D01*
Y-341563D01*
X754432Y-341272D01*
X754869Y-341563D01*
Y-342147D01*
X754432Y-342438D01*
G01X728182Y-386855D02*
Y-369355D01*
X725562Y-372855D01*
G01Y-386855D02*
X730802D01*
G01X830015Y-369355D02*
Y-386855D01*
X838749D01*
G01X847734Y-372272D02*
X849044Y-370522D01*
X850572Y-369647D01*
X852319Y-369355D01*
X854502Y-369938D01*
X856030Y-371397D01*
X856467Y-373146D01*
X856249Y-374897D01*
X855375Y-376355D01*
X851009Y-379272D01*
X849044Y-381313D01*
X847734Y-384231D01*
X847297Y-386855D01*
X856467D01*
G01X870692Y-378105D02*
X875059D01*
Y-383355D01*
X873749Y-385105D01*
X872220Y-386272D01*
X870037Y-386855D01*
X867854Y-386272D01*
X866325Y-385105D01*
X865015Y-383355D01*
X864142Y-381313D01*
X863705Y-378980D01*
Y-376938D01*
X864142Y-375189D01*
X865015Y-373146D01*
X866325Y-371397D01*
X867635Y-370230D01*
X869382Y-369355D01*
X870910D01*
X872657Y-369938D01*
X873967Y-371105D01*
G01X881860Y-386855D02*
Y-369355D01*
X891904Y-386855D01*
Y-369355D01*
G01X899579Y-386855D02*
Y-369355D01*
X903945D01*
X905692Y-370230D01*
X907002Y-371397D01*
X908094Y-373146D01*
X908967Y-375189D01*
X909185Y-378105D01*
X908967Y-381022D01*
X908094Y-383064D01*
X907002Y-384814D01*
X905692Y-385980D01*
X903945Y-386855D01*
X899579D01*
G01X830015Y-324355D02*
Y-341855D01*
X838749D01*
G01X855812D02*
Y-330189D01*
G01Y-332230D02*
X854939Y-331064D01*
X853628Y-330480D01*
X852100Y-330189D01*
X850572Y-330772D01*
X849262Y-331938D01*
X848388Y-333688D01*
X847952Y-336022D01*
X848388Y-338355D01*
X849262Y-340105D01*
X850572Y-341272D01*
X852100Y-341855D01*
X853628Y-341563D01*
X854939Y-340689D01*
X855812Y-339522D01*
G01X864797Y-347105D02*
X866107Y-347688D01*
X867854Y-347105D01*
X868945Y-345939D01*
X869819Y-344480D01*
X871128Y-339814D01*
X873967Y-330189D01*
G01X866980D02*
X871128Y-339814D01*
G01X883607Y-333980D02*
X890594D01*
X889939Y-331938D01*
X888847Y-330772D01*
X887319Y-330189D01*
X885790Y-330480D01*
X884480Y-331355D01*
X883607Y-333397D01*
X883170Y-335147D01*
Y-336897D01*
X883607Y-338647D01*
X884699Y-340397D01*
X886009Y-341563D01*
X887537Y-341855D01*
X889065Y-341272D01*
X890594Y-339522D01*
G01X901325Y-341855D02*
Y-330189D01*
G01Y-332522D02*
X902417Y-331355D01*
X903509Y-330480D01*
X905037Y-330189D01*
X906128Y-330480D01*
X907439Y-331355D01*
G01X994432Y-386855D02*
X992685Y-386563D01*
X991157Y-385397D01*
X989847Y-383647D01*
X988973Y-381605D01*
X988537Y-379272D01*
Y-376938D01*
X988973Y-374605D01*
X989847Y-372563D01*
X991157Y-370814D01*
X992685Y-369647D01*
X994432Y-369355D01*
X996178Y-369647D01*
X997707Y-370814D01*
X999017Y-372563D01*
X999891Y-374605D01*
X1000327Y-376938D01*
Y-379272D01*
X999891Y-381605D01*
X999017Y-383647D01*
X997707Y-385397D01*
X996178Y-386563D01*
X994432Y-386855D01*
G01X996178Y-382188D02*
X998799Y-386855D01*
G01X1007129Y-369355D02*
Y-381897D01*
X1008002Y-384522D01*
X1009749Y-386272D01*
X1011932Y-386855D01*
X1014115Y-386272D01*
X1015862Y-384522D01*
X1016735Y-381897D01*
Y-369355D01*
G01X1026812D02*
X1032052D01*
G01X1029432D02*
Y-386855D01*
G01X1026812D02*
X1032052D01*
G01X1041910D02*
Y-369355D01*
X1051954Y-386855D01*
Y-369355D01*
G01X1069235Y-370814D02*
X1067925Y-369938D01*
X1066397Y-369355D01*
X1064650D01*
X1062685Y-370230D01*
X1061157Y-371688D01*
X1060065Y-373439D01*
X1059192Y-376355D01*
X1058973Y-378980D01*
X1059410Y-381605D01*
X1060065Y-383355D01*
X1061375Y-385105D01*
X1062904Y-386272D01*
X1064432Y-386855D01*
X1065960D01*
X1067489Y-386272D01*
X1068799Y-385397D01*
X1069891Y-384231D01*
G01X1081932Y-386855D02*
Y-378980D01*
X1077565Y-369355D01*
G01X1086299D02*
X1081932Y-378980D01*
G01X972129Y-341855D02*
Y-324355D01*
X976495D01*
X978242Y-325230D01*
X979552Y-326397D01*
X980644Y-328146D01*
X981517Y-330189D01*
X981735Y-333105D01*
X981517Y-336022D01*
X980644Y-338064D01*
X979552Y-339814D01*
X978242Y-340980D01*
X976495Y-341855D01*
X972129D01*
G01X991157Y-333980D02*
X998144D01*
X997489Y-331938D01*
X996397Y-330772D01*
X994869Y-330189D01*
X993340Y-330480D01*
X992030Y-331355D01*
X991157Y-333397D01*
X990720Y-335147D01*
Y-336897D01*
X991157Y-338647D01*
X992249Y-340397D01*
X993559Y-341563D01*
X995087Y-341855D01*
X996615Y-341272D01*
X998144Y-339522D01*
G01X1008657Y-339814D02*
X1009749Y-340980D01*
X1011277Y-341855D01*
X1012587D01*
X1013897Y-341272D01*
X1014770Y-340397D01*
X1015207Y-339231D01*
X1014989Y-337480D01*
X1014115Y-336605D01*
X1010185Y-334855D01*
X1009312Y-332813D01*
X1009749Y-331355D01*
X1010622Y-330480D01*
X1011932Y-330189D01*
X1013242Y-330480D01*
X1014552Y-331355D01*
G01X1029432Y-330189D02*
Y-341855D01*
G01Y-325522D02*
X1028995Y-325230D01*
Y-324647D01*
X1029432Y-324355D01*
X1029869Y-324647D01*
Y-325230D01*
X1029432Y-325522D01*
G01X1043875Y-346230D02*
X1045404Y-347397D01*
X1047150Y-347688D01*
X1048678Y-347397D01*
X1049989Y-345939D01*
X1050862Y-343897D01*
Y-330189D01*
G01Y-332522D02*
X1049989Y-331355D01*
X1048678Y-330480D01*
X1047150Y-330189D01*
X1045404Y-330772D01*
X1044312Y-331938D01*
X1043438Y-333980D01*
X1043002Y-336022D01*
X1043220Y-337772D01*
X1044094Y-339814D01*
X1045404Y-341272D01*
X1047150Y-341855D01*
X1048460Y-341563D01*
X1049989Y-340397D01*
X1050862Y-339231D01*
G01X1060720Y-341855D02*
Y-330189D01*
G01Y-333105D02*
X1061594Y-331647D01*
X1062904Y-330480D01*
X1064650Y-330189D01*
X1066178Y-330480D01*
X1067489Y-331647D01*
X1068144Y-333688D01*
Y-341855D01*
G01X1078657Y-333980D02*
X1085644D01*
X1084989Y-331938D01*
X1083897Y-330772D01*
X1082369Y-330189D01*
X1080840Y-330480D01*
X1079530Y-331355D01*
X1078657Y-333397D01*
X1078220Y-335147D01*
Y-336897D01*
X1078657Y-338647D01*
X1079749Y-340397D01*
X1081059Y-341563D01*
X1082587Y-341855D01*
X1084115Y-341272D01*
X1085644Y-339522D01*
G01X1096375Y-341855D02*
Y-330189D01*
G01Y-332522D02*
X1097467Y-331355D01*
X1098559Y-330480D01*
X1100087Y-330189D01*
X1101178Y-330480D01*
X1102489Y-331355D01*
G01X1143132Y-369355D02*
X1141385Y-369938D01*
X1140075Y-371397D01*
X1139202Y-373146D01*
X1138547Y-375480D01*
X1138329Y-378105D01*
X1138547Y-380730D01*
X1139202Y-383064D01*
X1140075Y-384814D01*
X1141385Y-386272D01*
X1143132Y-386855D01*
X1144878Y-386272D01*
X1146189Y-384814D01*
X1147062Y-383064D01*
X1147717Y-380730D01*
X1147935Y-378105D01*
X1147717Y-375480D01*
X1147062Y-373146D01*
X1146189Y-371397D01*
X1144878Y-369938D01*
X1143132Y-369355D01*
G01X1156484Y-379564D02*
X1158012Y-377522D01*
X1159322Y-376355D01*
X1161069Y-375772D01*
X1162597Y-376355D01*
X1163689Y-377522D01*
X1164562Y-379272D01*
X1164780Y-381313D01*
X1164562Y-383064D01*
X1163689Y-384814D01*
X1162378Y-386272D01*
X1160850Y-386855D01*
X1159104Y-386272D01*
X1157575Y-384522D01*
X1156702Y-381897D01*
X1156484Y-378980D01*
X1156920Y-375189D01*
X1157575Y-373146D01*
X1158667Y-371105D01*
X1160195Y-369647D01*
X1161724Y-369355D01*
X1163252Y-369938D01*
X1164344Y-371397D01*
G01X1174202Y-387438D02*
X1182062Y-369355D01*
G01X1191484Y-372272D02*
X1192794Y-370522D01*
X1194322Y-369647D01*
X1196069Y-369355D01*
X1198252Y-369938D01*
X1199780Y-371397D01*
X1200217Y-373146D01*
X1199999Y-374897D01*
X1199125Y-376355D01*
X1194759Y-379272D01*
X1192794Y-381313D01*
X1191484Y-384231D01*
X1191047Y-386855D01*
X1200217D01*
G01X1213132D02*
Y-369355D01*
X1210512Y-372855D01*
G01Y-386855D02*
X1215752D01*
G01X1226702Y-387438D02*
X1234562Y-369355D01*
G01X1243984Y-372272D02*
X1245294Y-370522D01*
X1246822Y-369647D01*
X1248569Y-369355D01*
X1250752Y-369938D01*
X1252280Y-371397D01*
X1252717Y-373146D01*
X1252499Y-374897D01*
X1251625Y-376355D01*
X1247259Y-379272D01*
X1245294Y-381313D01*
X1243984Y-384231D01*
X1243547Y-386855D01*
X1252717D01*
G01X1265632Y-369355D02*
X1263885Y-369938D01*
X1262575Y-371397D01*
X1261702Y-373146D01*
X1261047Y-375480D01*
X1260829Y-378105D01*
X1261047Y-380730D01*
X1261702Y-383064D01*
X1262575Y-384814D01*
X1263885Y-386272D01*
X1265632Y-386855D01*
X1267378Y-386272D01*
X1268689Y-384814D01*
X1269562Y-383064D01*
X1270217Y-380730D01*
X1270435Y-378105D01*
X1270217Y-375480D01*
X1269562Y-373146D01*
X1268689Y-371397D01*
X1267378Y-369938D01*
X1265632Y-369355D01*
G01X1283132Y-386855D02*
Y-369355D01*
X1280512Y-372855D01*
G01Y-386855D02*
X1285752D01*
G01X1300195D02*
X1300632Y-383064D01*
X1301287Y-379855D01*
X1302160Y-376938D01*
X1303252Y-373730D01*
X1304999Y-369355D01*
X1296265D01*
G01X1190829Y-341855D02*
Y-324355D01*
X1195195D01*
X1196942Y-325230D01*
X1198252Y-326397D01*
X1199344Y-328146D01*
X1200217Y-330189D01*
X1200435Y-333105D01*
X1200217Y-336022D01*
X1199344Y-338064D01*
X1198252Y-339814D01*
X1196942Y-340980D01*
X1195195Y-341855D01*
X1190829D01*
G01X1217062D02*
Y-330189D01*
G01Y-332230D02*
X1216189Y-331064D01*
X1214878Y-330480D01*
X1213350Y-330189D01*
X1211822Y-330772D01*
X1210512Y-331938D01*
X1209638Y-333688D01*
X1209202Y-336022D01*
X1209638Y-338355D01*
X1210512Y-340105D01*
X1211822Y-341272D01*
X1213350Y-341855D01*
X1214878Y-341563D01*
X1216189Y-340689D01*
X1217062Y-339522D01*
G01X1230632Y-324355D02*
Y-341855D01*
G01X1227575Y-330189D02*
X1233689D01*
G01X1244857Y-333980D02*
X1251844D01*
X1251189Y-331938D01*
X1250097Y-330772D01*
X1248569Y-330189D01*
X1247040Y-330480D01*
X1245730Y-331355D01*
X1244857Y-333397D01*
X1244420Y-335147D01*
Y-336897D01*
X1244857Y-338647D01*
X1245949Y-340397D01*
X1247259Y-341563D01*
X1248787Y-341855D01*
X1250315Y-341272D01*
X1251844Y-339522D01*
M02*
